G04 ================== begin FILE IDENTIFICATION RECORD ==================*
G04 Layout Name:  9052_F0T_PDB_Converter_Brick_F_V03_1208_1600.brd*
G04 Film Name:    sst*
G04 File Format:  Gerber RS274X*
G04 File Origin:  Cadence Allegro 17.2-S081*
G04 Origin Date:  Wed Dec 21 09:54:59 2022*
G04 *
G04 Layer:  DRAWING FORMAT/TITLE_BLOCK_A*
G04 Layer:  BOARD GEOMETRY/DESIGN_OUTLINE*
G04 Layer:  BOARD GEOMETRY/CUTOUT*
G04 Layer:  BOARD GEOMETRY/OUTLINE*
G04 Layer:  DRAWING FORMAT/TITLE_BLOCK*
G04 Layer:  MANUFACTURING/TP_TEXT_TOP*
G04 Layer:  REF DES/SILKSCREEN_TOP*
G04 Layer:  PACKAGE GEOMETRY/SILKSCREEN_TOP*
G04 Layer:  MANUFACTURING/PHOTOPLOT_OUTLINE*
G04 Layer:  DRAWING FORMAT/TITLE_DATA_SST*
G04 Layer:  BOARD GEOMETRY/SILKSCREEN_TOP*
G04 *
G04 Offset:    (0.00 0.00)*
G04 Mirror:    No*
G04 Mode:      Positive*
G04 Rotation:  0*
G04 FullContactRelief:  No*
G04 UndefLineWidth:     6.00*
G04 ================== end FILE IDENTIFICATION RECORD ====================*
%FSLAX25Y25*MOIN*%
%IR0*IPPOS*OFA0.00000B0.00000*MIA0B0*SFA1.00000B1.00000*%
%ADD10C,.01*%
%ADD11C,.006*%
%ADD12C,.067*%
G75*
%LPD*%
G75*
G36*
G01X61100Y312500D02*
Y316500D01*
X57100Y314500D01*
X61100Y312500D01*
G37*
G36*
G01X109827Y252752D02*
Y264248D01*
X112976D01*
Y252752D01*
X109827D01*
G37*
G36*
G01X171815Y217185D02*
X175371Y215999D01*
X173001Y213629D01*
X171815Y217185D01*
G37*
G36*
G01X175381Y559700D02*
G02Y518300I1J-20700D01*
G01Y559700D01*
G37*
G36*
G01X189644Y209604D02*
X205156D01*
Y207004D01*
X189644D01*
Y209604D01*
G37*
G36*
G01X223381Y559700D02*
G02Y518300I1J-20700D01*
G01Y559700D01*
G37*
G36*
G01X288700Y230158D02*
G02X247300I-20700J-1D01*
G01X288700D01*
G37*
G36*
G01X258819Y506524D02*
X248819D01*
X253819Y496524D01*
X258819Y506524D01*
G37*
G36*
G01X271381Y559700D02*
G02Y518300I1J-20700D01*
G01Y559700D01*
G37*
G36*
G01X294752Y179385D02*
X298752D01*
X296752Y175385D01*
X294752Y179385D01*
G37*
G36*
G01X333200Y230158D02*
G02X291800I-20700J-1D01*
G01X333200D01*
G37*
G36*
G01X377700D02*
G02X336300I-20700J-1D01*
G01X377700D01*
G37*
G36*
G01X332861Y559700D02*
G02Y518300I1J-20700D01*
G01Y559700D01*
G37*
G36*
G01X377722Y37182D02*
X377222Y37732D01*
X381357Y42030D01*
X380868Y47460D01*
X377022Y51432D01*
X377272Y52132D01*
X377972Y52232D01*
X380693Y49404D01*
X380585Y50600D01*
X381825Y51600D01*
X382825Y51650D01*
X383775Y52100D01*
X385925D01*
X386475Y51850D01*
X387625Y51000D01*
X387825D01*
X388225Y51400D01*
X389025Y51300D01*
X389375Y50900D01*
Y50364D01*
X391172Y52232D01*
X391872Y52132D01*
X392122Y51432D01*
X389375Y48595D01*
Y47550D01*
X389125Y47250D01*
X388525D01*
X387929Y41883D01*
X388023Y41785D01*
X388075Y41750D01*
G02X388698Y41083I-1089J-1641D01*
G01X391922Y37732D01*
X391422Y37182D01*
X390772Y37232D01*
X388778Y39291D01*
G02X385325Y39050I-1792J818D01*
G01X381625D01*
X381498Y40460D01*
X378372Y37232D01*
X377722Y37182D01*
G37*
G36*
G01X378000Y36800D02*
X391150D01*
Y34500D01*
X378000D01*
Y36800D01*
G37*
G36*
G01X380861Y559700D02*
G02Y518300I1J-20700D01*
G01Y559700D01*
G37*
G36*
G01X449200Y230158D02*
G02X407800I-20700J-1D01*
G01X449200D01*
G37*
G36*
G01X416299Y506524D02*
X406299D01*
X411299Y496524D01*
X416299Y506524D01*
G37*
G36*
G01X428861Y559700D02*
G02Y518300I1J-20700D01*
G01Y559700D01*
G37*
G36*
G01X493200Y230158D02*
G02X451800I-20700J-1D01*
G01X493200D01*
G37*
G36*
G01X537200D02*
G02X495800I-20700J-1D01*
G01X537200D01*
G37*
G36*
G01X490342Y559700D02*
G02Y518300I1J-20700D01*
G01Y559700D01*
G37*
G36*
G01X538342D02*
G02Y518300I1J-20700D01*
G01Y559700D01*
G37*
G36*
G01X547993Y37103D02*
X539370D01*
Y73133D01*
X590132D01*
Y62799D01*
X547993D01*
Y37103D01*
G37*
G36*
G01X599200Y230158D02*
G02X557800I-20700J-1D01*
G01X599200D01*
G37*
G36*
G01X573780Y506524D02*
X563780D01*
X568780Y496524D01*
X573780Y506524D01*
G37*
G36*
G01X586342Y559700D02*
G02Y518300I1J-20700D01*
G01Y559700D01*
G37*
G36*
G01X643200Y230158D02*
G02X601800I-20700J-1D01*
G01X643200D01*
G37*
G36*
G01X687200D02*
G02X645800I-20700J-1D01*
G01X687200D01*
G37*
G36*
G01X647823Y559700D02*
G02Y518300I1J-20700D01*
G01Y559700D01*
G37*
G36*
G01X693500Y50637D02*
Y51837D01*
X694700Y51237D01*
X693500Y50637D01*
G37*
G36*
G01X756681Y230158D02*
G02X715281I-20700J-1D01*
G01X756681D01*
G37*
G36*
G01X695823Y559700D02*
G02Y518300I1J-20700D01*
G01Y559700D01*
G37*
G36*
G01X731261Y506524D02*
X721261D01*
X726261Y496524D01*
X731261Y506524D01*
G37*
G36*
G01X743823Y559700D02*
G02Y518300I1J-20700D01*
G01Y559700D01*
G37*
G36*
G01X800681Y230158D02*
G02X759281I-20700J-1D01*
G01X800681D01*
G37*
G36*
G01X844681D02*
G02X803281I-20700J-1D01*
G01X844681D01*
G37*
G36*
G01X834559Y168908D02*
X830559D01*
X832559Y164908D01*
X834559Y168908D01*
G37*
G36*
G01X960488Y55545D02*
X951934Y63924D01*
X936468D01*
Y74258D01*
X987649D01*
Y63924D01*
X964922D01*
X987649Y43046D01*
Y29151D01*
X967715Y48423D01*
X936468Y28104D01*
Y41475D01*
X960488Y55545D01*
G37*
G36*
G01X1009000Y88038D02*
X1013000D01*
X1011000Y92038D01*
X1009000Y88038D01*
G37*
G36*
G01X1022278Y174743D02*
X1024578D01*
Y177043D01*
X1022278D01*
Y174743D01*
G37*
G36*
G01X1076393Y181467D02*
X1080393D01*
X1078393Y177467D01*
X1076393Y181467D01*
G37*
G36*
G01X1114600Y92760D02*
Y94760D01*
X1112600Y93760D01*
X1114600Y92760D01*
G37*
G36*
G01X1110500Y175745D02*
Y179313D01*
X1114068Y177529D01*
X1110500Y175745D01*
G37*
G36*
G01X1141038Y92400D02*
Y88400D01*
X1145038Y90400D01*
X1141038Y92400D01*
G37*
G36*
G01X1206324Y288929D02*
Y284929D01*
X1210324Y286929D01*
X1206324Y288929D01*
G37*
%LPC*%
G75*
G36*
G01X384572Y45372D02*
X382206Y47831D01*
X382125Y49100D01*
X387025D01*
X386946Y47840D01*
X384572Y45372D01*
G37*
G36*
G01X383734Y44501D02*
X382501Y43219D01*
X382326Y45954D01*
X383734Y44501D01*
G37*
G36*
G01X386657Y43205D02*
X385410Y44501D01*
X386829Y45966D01*
X386657Y43205D01*
G37*
G36*
G01X386325Y41800D02*
G03X385025Y40450I849J-2119D01*
G01X382675Y40500D01*
X382604Y41603D01*
X384572Y43635D01*
X386342Y41807D01*
X386325Y41800D01*
G37*
G54D12*
X185224Y539000D03*
X233224D03*
X268000Y220315D03*
X281224Y539000D03*
X312500Y220315D03*
X357000D03*
X342704Y539000D03*
X390704D03*
X428500Y220315D03*
X438704Y539000D03*
X472500Y220315D03*
X516500D03*
X500185Y539000D03*
X548185D03*
X578500Y220315D03*
X596185Y539000D03*
X622500Y220315D03*
X666500D03*
X657666Y539000D03*
X735981Y220315D03*
X705666Y539000D03*
X753666D03*
X779981Y220315D03*
X823981D03*
%LPD*%
G75*
G36*
G01X383225Y48050D02*
X385925D01*
Y47300D01*
X383225D01*
Y48050D01*
G37*
G54D10*
G01X383800Y70400D02*
X384900Y71000D01*
Y66000D01*
G01X377300Y68700D02*
X382500D01*
X382400Y69400D01*
X382300Y69700D01*
X382100Y70100D01*
X381800Y70500D01*
X381300Y70900D01*
X380900Y71100D01*
X380600Y71200D01*
X380100Y71300D01*
X379700D01*
X379200Y71200D01*
X378900Y71100D01*
X378500Y70900D01*
X378100Y70600D01*
X378000Y70500D01*
X377700Y70100D01*
X377500Y69700D01*
X377400Y69400D01*
X377300Y68800D01*
Y68500D01*
X377400Y68000D01*
X377500Y67700D01*
X377700Y67300D01*
X378000Y66900D01*
X378500Y66500D01*
X378900Y66300D01*
X379200Y66200D01*
X379800Y66100D01*
X379900D01*
X380600Y66200D01*
X380900Y66300D01*
X381100Y66400D01*
X381700Y66800D01*
X382100Y67300D01*
G01X376600Y92500D02*
Y82400D01*
G01Y92500D02*
X379100D01*
G02Y87500I0J-2500D01*
G01X376600D01*
G01X382700Y92500D02*
Y82400D01*
G01X387510Y84800D02*
G03I-2410J0D01*
G54D11*
G01X-297025Y-1013390D02*
Y1828909D01*
X3691357D01*
Y-1013390D01*
X-297025D01*
G01X4093Y-769672D02*
Y-844672D01*
X504093D01*
Y-769672D01*
X4093D01*
G01X0Y518622D02*
G03X11811Y506811I11811J0D01*
G01X37795D01*
G02X39764Y504843I0J-1968D01*
G01Y459567D01*
G02X37795Y457598I-1969J0D01*
G01X11811D01*
G03X0Y445787I0J-11811D01*
G01Y136102D01*
G03X11811Y124291I11811J0D01*
G01X37795D01*
G02X39764Y122323I0J-1969D01*
G01Y77047D01*
G02X37795Y75079I-1969J1D01*
G01X11811D01*
G03X0Y63268I0J-11811D01*
G01Y19685D01*
G03X19685Y0I19685J0D01*
G01X1271654D01*
G03X1291339Y19685I0J19685D01*
G01Y559055D01*
G03X1271654Y578740I-19685J0D01*
G01X19685D01*
G03X0Y559055I0J-19685D01*
G01Y518622D01*
G01X16093Y-834672D02*
Y-839672D01*
G01X14636Y-834672D02*
X17550D01*
G01X22460Y-839672D02*
X19926D01*
Y-834672D01*
X22460D01*
G01X21446Y-837089D02*
X19926D01*
G01X25026Y-834672D02*
Y-839672D01*
X27560D01*
G01X31393Y-839839D02*
X31266Y-839755D01*
Y-839589D01*
X31393Y-839505D01*
X31520Y-839589D01*
Y-839755D01*
X31393Y-839839D01*
G01Y-837589D02*
X31266Y-837505D01*
Y-837339D01*
X31393Y-837255D01*
X31520Y-837339D01*
Y-837505D01*
X31393Y-837589D01*
G01X36176Y-841339D02*
X35543Y-840505D01*
X35226Y-839672D01*
Y-836339D01*
X35543Y-835505D01*
X36176Y-834672D01*
G01X41593D02*
X41086Y-834839D01*
X40706Y-835255D01*
X40453Y-835755D01*
X40263Y-836422D01*
X40200Y-837172D01*
X40263Y-837922D01*
X40453Y-838589D01*
X40706Y-839089D01*
X41086Y-839505D01*
X41593Y-839672D01*
X42100Y-839505D01*
X42480Y-839089D01*
X42733Y-838589D01*
X42923Y-837922D01*
X42986Y-837172D01*
X42923Y-836422D01*
X42733Y-835755D01*
X42480Y-835255D01*
X42100Y-834839D01*
X41593Y-834672D01*
G01X45300Y-838672D02*
X45680Y-839255D01*
X46186Y-839589D01*
X46756Y-839672D01*
X47263Y-839589D01*
X47770Y-839172D01*
X48086Y-838672D01*
X48150Y-838172D01*
X48023Y-837589D01*
X47580Y-837172D01*
X47136Y-837005D01*
X46566D01*
G01X47136D02*
X47516Y-836755D01*
X47833Y-836339D01*
X47960Y-835839D01*
X47833Y-835339D01*
X47516Y-834922D01*
X46946Y-834672D01*
X46376Y-834755D01*
X45806Y-835089D01*
G01X52110Y-841339D02*
X52743Y-840505D01*
X53060Y-839672D01*
Y-836339D01*
X52743Y-835505D01*
X52110Y-834672D01*
G01X55500Y-838672D02*
X55880Y-839255D01*
X56386Y-839589D01*
X56956Y-839672D01*
X57463Y-839589D01*
X57970Y-839172D01*
X58286Y-838672D01*
X58350Y-838172D01*
X58223Y-837589D01*
X57780Y-837172D01*
X57336Y-837005D01*
X56766D01*
G01X57336D02*
X57716Y-836755D01*
X58033Y-836339D01*
X58160Y-835839D01*
X58033Y-835339D01*
X57716Y-834922D01*
X57146Y-834672D01*
X56576Y-834755D01*
X56006Y-835089D01*
G01X60790Y-835505D02*
X61170Y-835005D01*
X61613Y-834755D01*
X62120Y-834672D01*
X62753Y-834839D01*
X63196Y-835255D01*
X63323Y-835755D01*
X63260Y-836255D01*
X63006Y-836672D01*
X61740Y-837505D01*
X61170Y-838089D01*
X60790Y-838922D01*
X60663Y-839672D01*
X63323D01*
G01X66966D02*
X67093Y-838589D01*
X67283Y-837672D01*
X67536Y-836839D01*
X67853Y-835922D01*
X68360Y-834672D01*
X65826D01*
G01X71370Y-838005D02*
X73016D01*
G01X76090Y-835505D02*
X76470Y-835005D01*
X76913Y-834755D01*
X77420Y-834672D01*
X78053Y-834839D01*
X78496Y-835255D01*
X78623Y-835755D01*
X78560Y-836255D01*
X78306Y-836672D01*
X77040Y-837505D01*
X76470Y-838089D01*
X76090Y-838922D01*
X75963Y-839672D01*
X78623D01*
G01X81000Y-838672D02*
X81380Y-839255D01*
X81886Y-839589D01*
X82456Y-839672D01*
X82963Y-839589D01*
X83470Y-839172D01*
X83786Y-838672D01*
X83850Y-838172D01*
X83723Y-837589D01*
X83280Y-837172D01*
X82836Y-837005D01*
X82266D01*
G01X82836D02*
X83216Y-836755D01*
X83533Y-836339D01*
X83660Y-835839D01*
X83533Y-835339D01*
X83216Y-834922D01*
X82646Y-834672D01*
X82076Y-834755D01*
X81506Y-835089D01*
G01X88253Y-839672D02*
Y-834672D01*
X85910Y-838255D01*
X89076D01*
G01X91200Y-838922D02*
X91580Y-839339D01*
X92023Y-839589D01*
X92593Y-839672D01*
X93163Y-839505D01*
X93606Y-839172D01*
X93923Y-838589D01*
X93986Y-837922D01*
X93860Y-837255D01*
X93543Y-836839D01*
X93100Y-836505D01*
X92656Y-836422D01*
X92213Y-836505D01*
X91643Y-836839D01*
X91833Y-834672D01*
X93543D01*
G01X101590Y-839672D02*
Y-834672D01*
X103996D01*
G01X103110Y-837089D02*
X101590D01*
G01X106310Y-839672D02*
X107893Y-834672D01*
X109476Y-839672D01*
G01X108906Y-837922D02*
X106880D01*
G01X111663Y-839672D02*
X114323Y-834672D01*
G01X111663D02*
X114323Y-839672D01*
G01X118093Y-839839D02*
X117966Y-839755D01*
Y-839589D01*
X118093Y-839505D01*
X118220Y-839589D01*
Y-839755D01*
X118093Y-839839D01*
G01Y-837589D02*
X117966Y-837505D01*
Y-837339D01*
X118093Y-837255D01*
X118220Y-837339D01*
Y-837505D01*
X118093Y-837589D01*
G01X122876Y-841339D02*
X122243Y-840505D01*
X121926Y-839672D01*
Y-836339D01*
X122243Y-835505D01*
X122876Y-834672D01*
G01X128293D02*
X127786Y-834839D01*
X127406Y-835255D01*
X127153Y-835755D01*
X126963Y-836422D01*
X126900Y-837172D01*
X126963Y-837922D01*
X127153Y-838589D01*
X127406Y-839089D01*
X127786Y-839505D01*
X128293Y-839672D01*
X128800Y-839505D01*
X129180Y-839089D01*
X129433Y-838589D01*
X129623Y-837922D01*
X129686Y-837172D01*
X129623Y-836422D01*
X129433Y-835755D01*
X129180Y-835255D01*
X128800Y-834839D01*
X128293Y-834672D01*
G01X132000Y-838672D02*
X132380Y-839255D01*
X132886Y-839589D01*
X133456Y-839672D01*
X133963Y-839589D01*
X134470Y-839172D01*
X134786Y-838672D01*
X134850Y-838172D01*
X134723Y-837589D01*
X134280Y-837172D01*
X133836Y-837005D01*
X133266D01*
G01X133836D02*
X134216Y-836755D01*
X134533Y-836339D01*
X134660Y-835839D01*
X134533Y-835339D01*
X134216Y-834922D01*
X133646Y-834672D01*
X133076Y-834755D01*
X132506Y-835089D01*
G01X138810Y-841339D02*
X139443Y-840505D01*
X139760Y-839672D01*
Y-836339D01*
X139443Y-835505D01*
X138810Y-834672D01*
G01X142200Y-838672D02*
X142580Y-839255D01*
X143086Y-839589D01*
X143656Y-839672D01*
X144163Y-839589D01*
X144670Y-839172D01*
X144986Y-838672D01*
X145050Y-838172D01*
X144923Y-837589D01*
X144480Y-837172D01*
X144036Y-837005D01*
X143466D01*
G01X144036D02*
X144416Y-836755D01*
X144733Y-836339D01*
X144860Y-835839D01*
X144733Y-835339D01*
X144416Y-834922D01*
X143846Y-834672D01*
X143276Y-834755D01*
X142706Y-835089D01*
G01X147616Y-839089D02*
X148060Y-839505D01*
X148566Y-839672D01*
X149073Y-839505D01*
X149516Y-839005D01*
X149833Y-838255D01*
X149960Y-837505D01*
Y-836589D01*
X149833Y-835839D01*
X149516Y-835172D01*
X149136Y-834839D01*
X148693Y-834672D01*
X148186Y-834839D01*
X147806Y-835172D01*
X147553Y-835672D01*
X147426Y-836339D01*
X147553Y-836922D01*
X147870Y-837505D01*
X148250Y-837839D01*
X148693Y-837922D01*
X149200Y-837755D01*
X149580Y-837339D01*
X149960Y-836589D01*
G01X153666Y-839672D02*
X153793Y-838589D01*
X153983Y-837672D01*
X154236Y-836839D01*
X154553Y-835922D01*
X155060Y-834672D01*
X152526D01*
G01X158070Y-838005D02*
X159716D01*
G01X162600Y-838672D02*
X162980Y-839255D01*
X163486Y-839589D01*
X164056Y-839672D01*
X164563Y-839589D01*
X165070Y-839172D01*
X165386Y-838672D01*
X165450Y-838172D01*
X165323Y-837589D01*
X164880Y-837172D01*
X164436Y-837005D01*
X163866D01*
G01X164436D02*
X164816Y-836755D01*
X165133Y-836339D01*
X165260Y-835839D01*
X165133Y-835339D01*
X164816Y-834922D01*
X164246Y-834672D01*
X163676Y-834755D01*
X163106Y-835089D01*
G01X167890Y-837589D02*
X168333Y-837005D01*
X168713Y-836672D01*
X169220Y-836505D01*
X169663Y-836672D01*
X169980Y-837005D01*
X170233Y-837505D01*
X170296Y-838089D01*
X170233Y-838589D01*
X169980Y-839089D01*
X169600Y-839505D01*
X169156Y-839672D01*
X168650Y-839505D01*
X168206Y-839005D01*
X167953Y-838255D01*
X167890Y-837422D01*
X168016Y-836339D01*
X168206Y-835755D01*
X168523Y-835172D01*
X168966Y-834755D01*
X169410Y-834672D01*
X169853Y-834839D01*
X170170Y-835255D01*
G01X174193Y-839672D02*
Y-834672D01*
X173433Y-835672D01*
G01Y-839672D02*
X174953D01*
G01X180053D02*
Y-834672D01*
X177710Y-838255D01*
X180876D01*
G01X118110Y41339D02*
X106299D01*
X32015Y37415D01*
G02Y57073I-519J9829D01*
G01X106299Y53150D01*
X118110D01*
G02Y41339I0J-5905D01*
G01Y53150D02*
G02Y41339I0J-5905D01*
G01X106299D01*
X32015Y37415D01*
G02Y57073I-519J9829D01*
G01X106299Y53150D01*
X118110D01*
G01X19921Y218504D02*
G02Y209843I0J-4330D01*
G02Y218504I0J4331D01*
G01Y209843D02*
G03Y218504I0J4331D01*
G03Y209843I0J-4330D01*
G01Y372047D02*
G02Y363386I0J-4330D01*
G02Y372047I0J4330D01*
G01Y363386D02*
G03Y372047I0J4330D01*
G03Y363386I0J-4330D01*
G01X32015Y545262D02*
X106299Y541339D01*
X118110D01*
G02Y529528I0J-5906D01*
G01X106299D01*
X32015Y525604D01*
G02Y545262I-519J9829D01*
G01D02*
G03Y525604I-519J-9829D01*
G01X106299Y529528D01*
X118110D01*
G03Y541339I0J5905D01*
G01X106299D01*
X32015Y545262D01*
G01X60630Y107520D02*
G02Y91929I0J-7796D01*
G02Y107520I0J7796D01*
G01Y91929D02*
G02Y107520I0J7796D01*
G02Y91929I0J-7796D01*
G01Y490000D02*
G02Y474409I0J-7796D01*
G02Y490000I0J7796D01*
G01Y474409D02*
G02Y490000I0J7796D01*
G02Y474409I0J-7796D01*
G01X82795Y107520D02*
G02Y91929I0J-7796D01*
G02Y107520I0J7796D01*
G01Y91929D02*
G02Y107520I0J7796D01*
G02Y91929I0J-7796D01*
G01Y490000D02*
G02Y474409I0J-7796D01*
G02Y490000I0J7796D01*
G01Y474409D02*
G02Y490000I0J7796D01*
G02Y474409I0J-7796D01*
G01X108858Y107520D02*
G02Y91929I0J-7796D01*
G02Y107520I0J7796D01*
G01Y91929D02*
G02Y107520I0J7796D01*
G02Y91929I0J-7796D01*
G01Y490000D02*
G02Y474409I0J-7796D01*
G02Y490000I0J7796D01*
G01Y474409D02*
G02Y490000I0J7796D01*
G02Y474409I0J-7796D01*
G01X178819Y281339D02*
G02Y273071I0J-4134D01*
G02Y281339I0J4134D01*
G01Y273071D02*
G03Y281339I0J4134D01*
G03Y273071I0J-4134D01*
G01X199093Y-769672D02*
Y-844672D01*
G01Y-819672D02*
X302093D01*
Y-794672D01*
G01X199093D02*
X302093D01*
G01X212816Y71022D02*
X212824Y71029D01*
G01X212493Y70938D02*
X212688Y71125D01*
G01X212170Y70857D02*
X212551Y71222D01*
G01X211848Y70774D02*
X212414Y71318D01*
G01X211525Y70691D02*
X212278Y71414D01*
G01X211202Y70610D02*
X212141Y71511D01*
G01X210879Y70526D02*
X212005Y71607D01*
G01X210557Y70444D02*
X211869Y71703D01*
G01X210233Y70362D02*
X211733Y71799D01*
G01X209959Y70325D02*
X211596Y71896D01*
G01X209792Y70393D02*
X211460Y71993D01*
G01X209624Y70458D02*
X211324Y72088D01*
G01X209456Y70526D02*
X211188Y72186D01*
G01X209289Y70591D02*
X211051Y72282D01*
G01X209121Y70657D02*
X210915Y72379D01*
G01X208953Y70724D02*
X210779Y72475D01*
G01X208785Y70789D02*
X210642Y72571D01*
G01X208617Y70857D02*
X210506Y72669D01*
G01X208449Y70922D02*
X210370Y72764D01*
G01X208281Y70987D02*
X210234Y72861D01*
G01X208112Y71053D02*
X210098Y72958D01*
G01X207944Y71119D02*
X209961Y73054D01*
G01X207775Y71185D02*
X209825Y73152D01*
G01X207607Y71250D02*
X209689Y73247D01*
G01X207438Y71315D02*
X209553Y73344D01*
G01X207269Y71380D02*
X209417Y73441D01*
G01X211202Y70610D02*
X211525Y70691D01*
G01X212816Y71022D02*
X212493Y70938D01*
G01X210879Y70526D02*
X211202Y70610D01*
G01X210557Y70444D02*
X210879Y70526D01*
G01X212170Y70857D02*
X212493Y70938D01*
G01X211525Y70691D02*
X211848Y70774D01*
G01D02*
X212170Y70857D01*
G01X210233Y70362D02*
X210557Y70444D01*
G01X212816Y71022D02*
X212824Y71029D01*
G01X212493Y70938D02*
X212688Y71125D01*
G01X212170Y70857D02*
X212551Y71222D01*
G01X211848Y70774D02*
X212414Y71318D01*
G01X211525Y70691D02*
X212278Y71414D01*
G01X211202Y70610D02*
X212141Y71511D01*
G01X210879Y70526D02*
X212005Y71607D01*
G01X210557Y70444D02*
X211869Y71703D01*
G01X210233Y70362D02*
X211733Y71799D01*
G01X209959Y70325D02*
X211596Y71896D01*
G01X209792Y70393D02*
X211460Y71993D01*
G01X209624Y70458D02*
X211324Y72088D01*
G01X209456Y70526D02*
X211188Y72186D01*
G01X209289Y70591D02*
X211051Y72282D01*
G01X209121Y70657D02*
X210915Y72379D01*
G01X208953Y70724D02*
X210779Y72475D01*
G01X208785Y70789D02*
X210642Y72571D01*
G01X208617Y70857D02*
X210506Y72669D01*
G01X208449Y70922D02*
X210370Y72764D01*
G01X208281Y70987D02*
X210234Y72861D01*
G01X208112Y71053D02*
X210098Y72958D01*
G01X207944Y71119D02*
X209961Y73054D01*
G01X207775Y71185D02*
X209825Y73152D01*
G01X207607Y71250D02*
X209689Y73247D01*
G01X207438Y71315D02*
X209553Y73344D01*
G01X207269Y71380D02*
X209417Y73441D01*
G01X211202Y70610D02*
X211525Y70691D01*
G01X212816Y71022D02*
X212493Y70938D01*
G01X210879Y70526D02*
X211202Y70610D01*
G01X210557Y70444D02*
X210879Y70526D01*
G01X212170Y70857D02*
X212493Y70938D01*
G01X211525Y70691D02*
X211848Y70774D01*
G01D02*
X212170Y70857D01*
G01X210233Y70362D02*
X210557Y70444D01*
G01X199495Y73012D02*
X203136Y76505D01*
G01X199311Y73062D02*
X202869Y76475D01*
G01X199128Y73114D02*
X202601Y76446D01*
G01X198943Y73164D02*
X202333Y76416D01*
G01X198759Y73214D02*
X202095Y76415D01*
G01X198575Y73266D02*
X201886Y76441D01*
G01X198391Y73316D02*
X201676Y76467D01*
G01X198216Y73376D02*
X201466Y76493D01*
G01X198049Y73442D02*
X201256Y76519D01*
G01X197881Y73508D02*
X201062Y76560D01*
G01X197714Y73575D02*
X200894Y76625D01*
G01X197546Y73641D02*
X200725Y76691D01*
G01X197379Y73708D02*
X200557Y76756D01*
G01X197211Y73774D02*
X200388Y76822D01*
G01X197060Y73856D02*
X200219Y76887D01*
G01X196909Y73939D02*
X200066Y76968D01*
G01X196758Y74021D02*
X199927Y77062D01*
G01X196607Y74104D02*
X199789Y77156D01*
G01X196456Y74187D02*
X199650Y77250D01*
G01X196305Y74269D02*
X199511Y77344D01*
G01X196160Y74357D02*
X199372Y77438D01*
G01X196025Y74455D02*
X199238Y77536D01*
G01X195891Y74553D02*
X199123Y77653D01*
G01X195756Y74650D02*
X199008Y77771D01*
G01X195621Y74749D02*
X198894Y77888D01*
G01X195487Y74846D02*
X198780Y78005D01*
G01X195352Y74945D02*
X198665Y78123D01*
G01X195226Y75051D02*
X198551Y78240D01*
G01X195107Y75165D02*
X198448Y78369D01*
G01X194988Y75277D02*
X198355Y78507D01*
G01X194869Y75390D02*
X198263Y78646D01*
G01X194750Y75503D02*
X198170Y78784D01*
G01X194631Y75616D02*
X198077Y78922D01*
G01X194511Y75729D02*
X197985Y79061D01*
G01X194404Y75854D02*
X197892Y79199D01*
G01X194303Y75983D02*
X197818Y79356D01*
G01X194201Y76113D02*
X197748Y79515D01*
G01X194100Y76243D02*
X197677Y79674D01*
G01X193999Y76373D02*
X197606Y79834D01*
G01X193897Y76503D02*
X197535Y79993D01*
G01X193796Y76633D02*
X197464Y80152D01*
G01X193704Y76772D02*
X197403Y80320D01*
G01X193622Y76920D02*
X197356Y80502D01*
G01X193539Y77068D02*
X197309Y80686D01*
G01X193456Y77216D02*
X197263Y80868D01*
G01X193374Y77364D02*
X197217Y81050D01*
G01X193291Y77512D02*
X197170Y81233D01*
G01X193209Y77660D02*
X197132Y81424D01*
G01X193139Y77821D02*
X197116Y81636D01*
G01X193074Y77985D02*
X197099Y81847D01*
G01X193008Y78149D02*
X197083Y82058D01*
G01X192942Y78313D02*
X197067Y82270D01*
G01X192876Y78477D02*
X197050Y82481D01*
G01X192811Y78642D02*
X197069Y82726D01*
G01X192754Y78814D02*
X197095Y82978D01*
G01X192703Y78993D02*
X197122Y83231D01*
G01X192652Y79171D02*
X197148Y83484D01*
G01X192602Y79350D02*
X197175Y83737D01*
G01X192551Y79529D02*
X197262Y84048D01*
G01X192501Y79708D02*
X197358Y84367D01*
G01X192463Y79899D02*
X197455Y84687D01*
G01X192426Y80091D02*
X197600Y85054D01*
G01X192389Y80282D02*
X197836Y85507D01*
G01X192352Y80474D02*
X198149Y86034D01*
G01X204164Y92033D02*
X192316Y80667D01*
G01X203955Y92058D02*
X192291Y80870D01*
G01X203745Y92084D02*
X192267Y81073D01*
G01X199495Y73012D02*
X203136Y76505D01*
G01X199311Y73062D02*
X202869Y76475D01*
G01X199128Y73114D02*
X202601Y76446D01*
G01X198943Y73164D02*
X202333Y76416D01*
G01X198759Y73214D02*
X202095Y76415D01*
G01X198575Y73266D02*
X201886Y76441D01*
G01X198391Y73316D02*
X201676Y76467D01*
G01X198216Y73376D02*
X201466Y76493D01*
G01X198049Y73442D02*
X201256Y76519D01*
G01X197881Y73508D02*
X201062Y76560D01*
G01X197714Y73575D02*
X200894Y76625D01*
G01X197546Y73641D02*
X200725Y76691D01*
G01X197379Y73708D02*
X200557Y76756D01*
G01X197211Y73774D02*
X200388Y76822D01*
G01X197060Y73856D02*
X200219Y76887D01*
G01X196909Y73939D02*
X200066Y76968D01*
G01X196758Y74021D02*
X199927Y77062D01*
G01X196607Y74104D02*
X199789Y77156D01*
G01X196456Y74187D02*
X199650Y77250D01*
G01X196305Y74269D02*
X199511Y77344D01*
G01X196160Y74357D02*
X199372Y77438D01*
G01X196025Y74455D02*
X199238Y77536D01*
G01X195891Y74553D02*
X199123Y77653D01*
G01X195756Y74650D02*
X199008Y77771D01*
G01X195621Y74749D02*
X198894Y77888D01*
G01X195487Y74846D02*
X198780Y78005D01*
G01X195352Y74945D02*
X198665Y78123D01*
G01X195226Y75051D02*
X198551Y78240D01*
G01X195107Y75165D02*
X198448Y78369D01*
G01X194988Y75277D02*
X198355Y78507D01*
G01X194869Y75390D02*
X198263Y78646D01*
G01X194750Y75503D02*
X198170Y78784D01*
G01X194631Y75616D02*
X198077Y78922D01*
G01X194511Y75729D02*
X197985Y79061D01*
G01X194404Y75854D02*
X197892Y79199D01*
G01X194303Y75983D02*
X197818Y79356D01*
G01X194201Y76113D02*
X197748Y79515D01*
G01X194100Y76243D02*
X197677Y79674D01*
G01X193999Y76373D02*
X197606Y79834D01*
G01X193897Y76503D02*
X197535Y79993D01*
G01X193796Y76633D02*
X197464Y80152D01*
G01X193704Y76772D02*
X197403Y80320D01*
G01X193622Y76920D02*
X197356Y80502D01*
G01X193539Y77068D02*
X197309Y80686D01*
G01X193456Y77216D02*
X197263Y80868D01*
G01X193374Y77364D02*
X197217Y81050D01*
G01X193291Y77512D02*
X197170Y81233D01*
G01X193209Y77660D02*
X197132Y81424D01*
G01X193139Y77821D02*
X197116Y81636D01*
G01X193074Y77985D02*
X197099Y81847D01*
G01X193008Y78149D02*
X197083Y82058D01*
G01X192942Y78313D02*
X197067Y82270D01*
G01X192876Y78477D02*
X197050Y82481D01*
G01X192811Y78642D02*
X197069Y82726D01*
G01X192754Y78814D02*
X197095Y82978D01*
G01X192703Y78993D02*
X197122Y83231D01*
G01X192652Y79171D02*
X197148Y83484D01*
G01X192602Y79350D02*
X197175Y83737D01*
G01X192551Y79529D02*
X197262Y84048D01*
G01X192501Y79708D02*
X197358Y84367D01*
G01X192463Y79899D02*
X197455Y84687D01*
G01X192426Y80091D02*
X197600Y85054D01*
G01X192389Y80282D02*
X197836Y85507D01*
G01X192352Y80474D02*
X198149Y86034D01*
G01X204164Y92033D02*
X192316Y80667D01*
G01X203955Y92058D02*
X192291Y80870D01*
G01X203745Y92084D02*
X192267Y81073D01*
G01X203535Y92111D02*
X192242Y81277D01*
G01X203315Y92127D02*
X192216Y81480D01*
G01X203087Y92136D02*
X192203Y81694D01*
G01X202860Y92145D02*
X192189Y81908D01*
G01X202632Y92153D02*
X192175Y82121D01*
G01X202405Y92162D02*
X192168Y82343D01*
G01X202159Y92153D02*
X192164Y82565D01*
G01X201911Y92143D02*
X192169Y82797D01*
G01X201662Y92131D02*
X192180Y83035D01*
G01X201413Y92120D02*
X192191Y83273D01*
G01X201165Y92109D02*
X192202Y83511D01*
G01X200888Y92070D02*
X192236Y83770D01*
G01X200610Y92031D02*
X192273Y84033D01*
G01X200332Y91992D02*
X192310Y84296D01*
G01X200055Y91953D02*
X192364Y84575D01*
G01X199743Y91881D02*
X192434Y84869D01*
G01X199427Y91804D02*
X192504Y85163D01*
G01X199109Y91727D02*
X192600Y85483D01*
G01X198763Y91623D02*
X192714Y85819D01*
G01X198390Y91491D02*
X192832Y86160D01*
G01X198015Y91359D02*
X193011Y86558D01*
G01X197560Y91150D02*
X193192Y86959D01*
G01X197092Y90929D02*
X193475Y87458D01*
G01X196464Y90553D02*
X193855Y88050D01*
G01X203535Y92111D02*
X192242Y81277D01*
G01X203315Y92127D02*
X192216Y81480D01*
G01X203087Y92136D02*
X192203Y81694D01*
G01X202860Y92145D02*
X192189Y81908D01*
G01X202632Y92153D02*
X192175Y82121D01*
G01X202405Y92162D02*
X192168Y82343D01*
G01X202159Y92153D02*
X192164Y82565D01*
G01X201911Y92143D02*
X192169Y82797D01*
G01X201662Y92131D02*
X192180Y83035D01*
G01X201413Y92120D02*
X192191Y83273D01*
G01X201165Y92109D02*
X192202Y83511D01*
G01X200888Y92070D02*
X192236Y83770D01*
G01X200610Y92031D02*
X192273Y84033D01*
G01X200332Y91992D02*
X192310Y84296D01*
G01X200055Y91953D02*
X192364Y84575D01*
G01X199743Y91881D02*
X192434Y84869D01*
G01X199427Y91804D02*
X192504Y85163D01*
G01X199109Y91727D02*
X192600Y85483D01*
G01X198763Y91623D02*
X192714Y85819D01*
G01X198390Y91491D02*
X192832Y86160D01*
G01X198015Y91359D02*
X193011Y86558D01*
G01X197560Y91150D02*
X193192Y86959D01*
G01X197092Y90929D02*
X193475Y87458D01*
G01X196464Y90553D02*
X193855Y88050D01*
G01X207100Y71445D02*
X209281Y73537D01*
G01X206931Y71511D02*
X209145Y73634D01*
G01X206762Y71576D02*
X209009Y73731D01*
G01X206592Y71641D02*
X208872Y73827D01*
G01X206423Y71705D02*
X208736Y73924D01*
G01X206252Y71768D02*
X208600Y74020D01*
G01X208464Y74117D02*
X206082Y71833D01*
G01X205912Y71897D02*
X208328Y74214D01*
G01X205742Y71961D02*
X210815Y76827D01*
G01X205571Y72023D02*
X211105Y77333D01*
G01X205400Y72087D02*
X211354Y77799D01*
G01X205228Y72149D02*
X211501Y78167D01*
G01X205056Y72212D02*
X211647Y78534D01*
G01X204884Y72273D02*
X211775Y78884D01*
G01X204710Y72334D02*
X211852Y79185D01*
G01X204536Y72395D02*
X211929Y79487D01*
G01X204360Y72452D02*
X212006Y79787D01*
G01X204183Y72509D02*
X212075Y80081D01*
G01X204000Y72563D02*
X212111Y80343D01*
G01X203800Y72597D02*
X212148Y80605D01*
G01X203570Y72604D02*
X212184Y80867D01*
G01X203340Y72609D02*
X212220Y81128D01*
G01X203110Y72617D02*
X212256Y81390D01*
G01X202880Y72623D02*
X212265Y81627D01*
G01X202649Y72630D02*
X212275Y81863D01*
G01X202419Y72636D02*
X212285Y82099D01*
G01X202194Y72647D02*
X212295Y82337D01*
G01X201979Y72668D02*
X212305Y82574D01*
G01X201763Y72688D02*
X212315Y82810D01*
G01X201547Y72708D02*
X212311Y83033D01*
G01X201332Y72729D02*
X212302Y83253D01*
G01X201116Y72749D02*
X212287Y83465D01*
G01X200900Y72769D02*
X212266Y83673D01*
G01X200696Y72799D02*
X212246Y83880D01*
G01X212220Y84082D02*
X200495Y72834D01*
G01X212187Y84278D02*
X206248Y78580D01*
G01X200295Y72870D02*
X204749Y77143D01*
G01X212155Y84474D02*
X206609Y79155D01*
G01X200095Y72905D02*
X204182Y76826D01*
G01X212121Y84670D02*
X206789Y79554D01*
G01X199895Y72940D02*
X203812Y76699D01*
G01X212084Y84861D02*
X206969Y79954D01*
G01X199694Y72975D02*
X203441Y76570D01*
G01X212038Y85044D02*
X207057Y80266D01*
G01X211993Y85227D02*
X207133Y80565D01*
G01X211946Y85410D02*
X207209Y80865D01*
G01X207100Y71445D02*
X209281Y73537D01*
G01X206931Y71511D02*
X209145Y73634D01*
G01X206762Y71576D02*
X209009Y73731D01*
G01X206592Y71641D02*
X208872Y73827D01*
G01X206423Y71705D02*
X208736Y73924D01*
G01X206252Y71768D02*
X208600Y74020D01*
G01X208464Y74117D02*
X206082Y71833D01*
G01X205912Y71897D02*
X208328Y74214D01*
G01X205742Y71961D02*
X210815Y76827D01*
G01X205571Y72023D02*
X211105Y77333D01*
G01X205400Y72087D02*
X211354Y77799D01*
G01X205228Y72149D02*
X211501Y78167D01*
G01X205056Y72212D02*
X211647Y78534D01*
G01X204884Y72273D02*
X211775Y78884D01*
G01X204710Y72334D02*
X211852Y79185D01*
G01X204536Y72395D02*
X211929Y79487D01*
G01X204360Y72452D02*
X212006Y79787D01*
G01X204183Y72509D02*
X212075Y80081D01*
G01X204000Y72563D02*
X212111Y80343D01*
G01X203800Y72597D02*
X212148Y80605D01*
G01X203570Y72604D02*
X212184Y80867D01*
G01X203340Y72609D02*
X212220Y81128D01*
G01X203110Y72617D02*
X212256Y81390D01*
G01X202880Y72623D02*
X212265Y81627D01*
G01X202649Y72630D02*
X212275Y81863D01*
G01X202419Y72636D02*
X212285Y82099D01*
G01X202194Y72647D02*
X212295Y82337D01*
G01X201979Y72668D02*
X212305Y82574D01*
G01X201763Y72688D02*
X212315Y82810D01*
G01X201547Y72708D02*
X212311Y83033D01*
G01X201332Y72729D02*
X212302Y83253D01*
G01X201116Y72749D02*
X212287Y83465D01*
G01X200900Y72769D02*
X212266Y83673D01*
G01X200696Y72799D02*
X212246Y83880D01*
G01X212220Y84082D02*
X200495Y72834D01*
G01X212187Y84278D02*
X206248Y78580D01*
G01X200295Y72870D02*
X204749Y77143D01*
G01X212155Y84474D02*
X206609Y79155D01*
G01X200095Y72905D02*
X204182Y76826D01*
G01X212121Y84670D02*
X206789Y79554D01*
G01X199895Y72940D02*
X203812Y76699D01*
G01X212084Y84861D02*
X206969Y79954D01*
G01X199694Y72975D02*
X203441Y76570D01*
G01X212038Y85044D02*
X207057Y80266D01*
G01X211993Y85227D02*
X207133Y80565D01*
G01X211946Y85410D02*
X207209Y80865D01*
G01X211900Y85593D02*
X207272Y81153D01*
G01X211848Y85770D02*
X207292Y81400D01*
G01X211788Y85940D02*
X207312Y81646D01*
G01X211729Y86110D02*
X207332Y81893D01*
G01X211668Y86280D02*
X207352Y82139D01*
G01X211609Y86450D02*
X207356Y82370D01*
G01X211549Y86619D02*
X207338Y82580D01*
G01X211476Y86777D02*
X207321Y82791D01*
G01X211401Y86932D02*
X207303Y83001D01*
G01X211326Y87087D02*
X207285Y83212D01*
G01X211251Y87243D02*
X207268Y83422D01*
G01X211177Y87398D02*
X207237Y83619D01*
G01X211101Y87553D02*
X207189Y83801D01*
G01X211015Y87698D02*
X207142Y83983D01*
G01X210924Y87838D02*
X207095Y84165D01*
G01X210833Y87977D02*
X207047Y84346D01*
G01X210741Y88117D02*
X207000Y84527D01*
G01X210650Y88257D02*
X206950Y84707D01*
G01X210558Y88396D02*
X206877Y84864D01*
G01X210467Y88535D02*
X206805Y85022D01*
G01X210359Y88659D02*
X206732Y85180D01*
G01X210249Y88781D02*
X206659Y85337D01*
G01X210140Y88903D02*
X206586Y85494D01*
G01X210030Y89025D02*
X206514Y85652D01*
G01X209920Y89147D02*
X206428Y85797D01*
G01X209810Y89268D02*
X206332Y85932D01*
G01X209700Y89390D02*
X206236Y86067D01*
G01X209580Y89502D02*
X206140Y86202D01*
G01X209455Y89610D02*
X206044Y86337D01*
G01X209329Y89717D02*
X205948Y86472D01*
G01X209205Y89824D02*
X205852Y86608D01*
G01X209079Y89930D02*
X205734Y86722D01*
G01X208954Y90037D02*
X205615Y86834D01*
G01X208821Y90138D02*
X205496Y86948D01*
G01X208684Y90233D02*
X205376Y87060D01*
G01X208547Y90328D02*
X205258Y87174D01*
G01X208410Y90424D02*
X205138Y87286D01*
G01X208272Y90520D02*
X205006Y87386D01*
G01X208135Y90615D02*
X204862Y87476D01*
G01X207988Y90701D02*
X204718Y87564D01*
G01X207838Y90785D02*
X204574Y87654D01*
G01X207688Y90868D02*
X204430Y87743D01*
G01X207538Y90952D02*
X204285Y87831D01*
G01X207388Y91035D02*
X204129Y87909D01*
G01X207237Y91116D02*
X203956Y87970D01*
G01X207072Y91187D02*
X203782Y88030D01*
G01X206909Y91257D02*
X203608Y88091D01*
G01X206746Y91327D02*
X203435Y88151D01*
G01X206582Y91398D02*
X203262Y88213D01*
G01X206419Y91468D02*
X203057Y88244D01*
G01X206245Y91529D02*
X202845Y88267D01*
G01X206067Y91586D02*
X202633Y88291D01*
G01X205889Y91642D02*
X202422Y88316D01*
G01X205711Y91698D02*
X202209Y88339D01*
G01X205533Y91755D02*
X201947Y88315D01*
G01X205348Y91805D02*
X201678Y88284D01*
G01X205155Y91847D02*
X201408Y88253D01*
G01X204961Y91888D02*
X201098Y88182D01*
G01X204768Y91930D02*
X200729Y88056D01*
G01X204575Y91972D02*
X200361Y87929D01*
G01X204375Y92007D02*
X199767Y87587D01*
G01X211900Y85593D02*
X207272Y81153D01*
G01X211848Y85770D02*
X207292Y81400D01*
G01X211788Y85940D02*
X207312Y81646D01*
G01X211729Y86110D02*
X207332Y81893D01*
G01X211668Y86280D02*
X207352Y82139D01*
G01X211609Y86450D02*
X207356Y82370D01*
G01X211549Y86619D02*
X207338Y82580D01*
G01X211476Y86777D02*
X207321Y82791D01*
G01X211401Y86932D02*
X207303Y83001D01*
G01X211326Y87087D02*
X207285Y83212D01*
G01X211251Y87243D02*
X207268Y83422D01*
G01X211177Y87398D02*
X207237Y83619D01*
G01X211101Y87553D02*
X207189Y83801D01*
G01X211015Y87698D02*
X207142Y83983D01*
G01X210924Y87838D02*
X207095Y84165D01*
G01X210833Y87977D02*
X207047Y84346D01*
G01X210741Y88117D02*
X207000Y84527D01*
G01X210650Y88257D02*
X206950Y84707D01*
G01X210558Y88396D02*
X206877Y84864D01*
G01X210467Y88535D02*
X206805Y85022D01*
G01X210359Y88659D02*
X206732Y85180D01*
G01X210249Y88781D02*
X206659Y85337D01*
G01X210140Y88903D02*
X206586Y85494D01*
G01X210030Y89025D02*
X206514Y85652D01*
G01X209920Y89147D02*
X206428Y85797D01*
G01X209810Y89268D02*
X206332Y85932D01*
G01X209700Y89390D02*
X206236Y86067D01*
G01X209580Y89502D02*
X206140Y86202D01*
G01X209455Y89610D02*
X206044Y86337D01*
G01X209329Y89717D02*
X205948Y86472D01*
G01X209205Y89824D02*
X205852Y86608D01*
G01X209079Y89930D02*
X205734Y86722D01*
G01X208954Y90037D02*
X205615Y86834D01*
G01X208821Y90138D02*
X205496Y86948D01*
G01X208684Y90233D02*
X205376Y87060D01*
G01X208547Y90328D02*
X205258Y87174D01*
G01X208410Y90424D02*
X205138Y87286D01*
G01X208272Y90520D02*
X205006Y87386D01*
G01X208135Y90615D02*
X204862Y87476D01*
G01X207988Y90701D02*
X204718Y87564D01*
G01X207838Y90785D02*
X204574Y87654D01*
G01X207688Y90868D02*
X204430Y87743D01*
G01X207538Y90952D02*
X204285Y87831D01*
G01X207388Y91035D02*
X204129Y87909D01*
G01X207237Y91116D02*
X203956Y87970D01*
G01X207072Y91187D02*
X203782Y88030D01*
G01X206909Y91257D02*
X203608Y88091D01*
G01X206746Y91327D02*
X203435Y88151D01*
G01X206582Y91398D02*
X203262Y88213D01*
G01X206419Y91468D02*
X203057Y88244D01*
G01X206245Y91529D02*
X202845Y88267D01*
G01X206067Y91586D02*
X202633Y88291D01*
G01X205889Y91642D02*
X202422Y88316D01*
G01X205711Y91698D02*
X202209Y88339D01*
G01X205533Y91755D02*
X201947Y88315D01*
G01X205348Y91805D02*
X201678Y88284D01*
G01X205155Y91847D02*
X201408Y88253D01*
G01X204961Y91888D02*
X201098Y88182D01*
G01X204768Y91930D02*
X200729Y88056D01*
G01X204575Y91972D02*
X200361Y87929D01*
G01X204375Y92007D02*
X199767Y87587D01*
G01X193819Y281339D02*
G02Y273071I0J-4134D01*
G02Y281339I0J4134D01*
G01Y273071D02*
G03Y281339I0J4134D01*
G03Y273071I0J-4134D01*
G01Y480354D02*
G02Y474055I0J-3149D01*
G02Y480354I0J3149D01*
G01Y474055D02*
G03Y480354I0J3149D01*
G03Y474055I0J-3149D01*
G01X242760Y73476D02*
X244316Y74969D01*
G01X242523Y73476D02*
X244365Y75242D01*
G01X242287Y73476D02*
X244411Y75514D01*
G01X242050Y73476D02*
X244460Y75788D01*
G01X241813Y73476D02*
X244509Y76061D01*
G01X241577Y73476D02*
X244555Y76334D01*
G01X241340Y73476D02*
X244604Y76607D01*
G01X241102Y73476D02*
X244651Y76880D01*
G01X240865Y73476D02*
X244699Y77154D01*
G01X240628Y73476D02*
X244748Y77427D01*
G01X240392Y73476D02*
X244795Y77700D01*
G01X240155Y73476D02*
X244843Y77974D01*
G01X239918Y73476D02*
X244891Y78247D01*
G01X239682Y73476D02*
X244939Y78519D01*
G01X239648Y73671D02*
X244986Y78793D01*
G01X239697Y73945D02*
X245035Y79066D01*
G01X239745Y74219D02*
X245083Y79339D01*
G01X239794Y74492D02*
X245130Y79612D01*
G01X239247Y74195D02*
X245179Y79885D01*
G01X238650Y73850D02*
X245226Y80159D01*
G01X238176Y73622D02*
X245274Y80432D01*
G01X237795Y73484D02*
X245323Y80705D01*
G01X237458Y73388D02*
X245370Y80978D01*
G01X237121Y73293D02*
X245418Y81251D01*
G01X236814Y73225D02*
X245466Y81524D01*
G01X236551Y73201D02*
X245514Y81798D01*
G01X236287Y73173D02*
X245561Y82070D01*
G01X236024Y73149D02*
X245610Y82344D01*
G01X235760Y73122D02*
X245658Y82618D01*
G01X235533Y73131D02*
X245705Y82890D01*
G01X235305Y73141D02*
X245754Y83163D01*
G01X245802Y83437D02*
X235084Y73156D01*
G01X234873Y73182D02*
X239431Y77553D01*
G01X245849Y83710D02*
X240516Y78593D01*
G01X234663Y73206D02*
X238910Y77280D01*
G01X245898Y83983D02*
X240563Y78866D01*
G01X234463Y73241D02*
X238528Y77141D01*
G01X245945Y84256D02*
X240611Y79139D01*
G01X245993Y84529D02*
X240659Y79413D01*
G01X234268Y73282D02*
X238154Y77010D01*
G01X234073Y73321D02*
X237883Y76977D01*
G01X246040Y84803D02*
X240707Y79686D01*
G01X233890Y73374D02*
X237612Y76943D01*
G01X246061Y85049D02*
X240755Y79959D01*
G01X233710Y73428D02*
X237341Y76910D01*
G01X246081Y85295D02*
X240803Y80232D01*
G01X233529Y73483D02*
X237080Y76888D01*
G01X246101Y85542D02*
X240851Y80506D01*
G01X246120Y85788D02*
X240741Y80628D01*
G01X233361Y73548D02*
X236860Y76904D01*
G01X233195Y73616D02*
X236640Y76920D01*
G01X246141Y86034D02*
X240601Y80719D01*
G01X246134Y86255D02*
X240449Y80801D01*
G01X233029Y73683D02*
X236430Y76945D01*
G01X232874Y73762D02*
X236243Y76994D01*
G01X246107Y86456D02*
X240293Y80880D01*
G01X246080Y86657D02*
X240129Y80949D01*
G01X232722Y73843D02*
X236057Y77043D01*
G01X246052Y86858D02*
X239957Y81011D01*
G01X232570Y73925D02*
X235886Y77106D01*
G01X232427Y74015D02*
X235733Y77186D01*
G01X246024Y87058D02*
X239778Y81066D01*
G01X232289Y74109D02*
X235580Y77267D01*
G01X232151Y74204D02*
X235453Y77373D01*
G01X232020Y74306D02*
X235333Y77485D01*
G01X231896Y74414D02*
X235223Y77606D01*
G01X231772Y74522D02*
X235137Y77750D01*
G01X231652Y74635D02*
X235050Y77895D01*
G01X231542Y74757D02*
X234997Y78070D01*
G01X231433Y74879D02*
X234945Y78248D01*
G01X231325Y75002D02*
X234923Y78454D01*
G01X231231Y75140D02*
X234908Y78667D01*
G01X231137Y75277D02*
X234928Y78913D01*
G01X231043Y75414D02*
X234964Y79175D01*
G01X230963Y75564D02*
X235089Y79522D01*
G01X236278Y80890D02*
X240097Y84554D01*
G01X230885Y75717D02*
X235215Y79870D01*
G01X230808Y75870D02*
X239897Y84588D01*
G01X230741Y76033D02*
X239697Y84624D01*
G01X230682Y76203D02*
X239496Y84658D01*
G01X230622Y76373D02*
X239284Y84683D01*
G01X230571Y76551D02*
X239059Y84694D01*
G01X230530Y76739D02*
X238835Y84706D01*
G01X227128Y73476D02*
X227247Y73590D01*
G01X226891Y73476D02*
X227296Y73864D01*
G01X230490Y76928D02*
X238610Y84718D01*
G01X226654Y73476D02*
X227343Y74137D01*
G01X230455Y77122D02*
X238386Y84730D01*
G01X230437Y77331D02*
X238138Y84719D01*
G01X226417Y73476D02*
X227391Y74410D01*
G01X230418Y77541D02*
X237885Y84704D01*
G01X226181Y73476D02*
X227439Y74683D01*
G01X225943Y73476D02*
X227488Y74957D01*
G01X230404Y77755D02*
X237632Y84688D01*
G01X230410Y77987D02*
X237378Y84672D01*
G01X225707Y73476D02*
X227536Y75230D01*
G01X230415Y78220D02*
X237125Y84657D01*
G01X225470Y73476D02*
X227583Y75503D01*
G01X225233Y73476D02*
X227631Y75776D01*
G01X230427Y78458D02*
X236861Y84630D01*
G01X230459Y78717D02*
X236563Y84572D01*
G01X224997Y73476D02*
X227679Y76050D01*
G01X230493Y78976D02*
X236265Y84514D01*
G01X224759Y73476D02*
X227728Y76324D01*
G01X224523Y73476D02*
X227776Y76596D01*
G01X230545Y79253D02*
X235968Y84455D01*
G01X230632Y79564D02*
X235670Y84397D01*
G01X224286Y73476D02*
X227823Y76869D01*
G01X224049Y73476D02*
X227871Y77143D01*
G01X230719Y79874D02*
X235315Y84283D01*
G01X230807Y80186D02*
X234940Y84151D01*
G01X223812Y73476D02*
X227920Y77416D01*
G01X230916Y80518D02*
X234566Y84019D01*
G01X223575Y73476D02*
X227968Y77689D01*
G01X223339Y73476D02*
X228016Y77963D01*
G01X231154Y80973D02*
X234115Y83813D01*
G01X223102Y73476D02*
X228063Y78236D01*
G01X222864Y73476D02*
X228111Y78509D01*
G01X222822Y73662D02*
X228160Y78783D01*
G01X222870Y73936D02*
X228208Y79056D01*
G01X222917Y74208D02*
X228256Y79329D01*
G01X222966Y74482D02*
X228303Y79602D01*
G01X222462Y74225D02*
X228352Y79876D01*
G01X221857Y73872D02*
X228400Y80148D01*
G01X221387Y73649D02*
X228448Y80422D01*
G01X221000Y73504D02*
X228496Y80696D01*
G01X220667Y73412D02*
X228543Y80969D01*
G01X220333Y73320D02*
X228592Y81242D01*
G01X220010Y73237D02*
X228640Y81516D01*
G01X219748Y73213D02*
X228688Y81789D01*
G01X219486Y73188D02*
X228736Y82062D01*
G01X219224Y73165D02*
X228784Y82335D01*
G01X218962Y73141D02*
X228832Y82608D01*
G01X218712Y73127D02*
X228880Y82882D01*
G01X218496Y73148D02*
X228928Y83155D01*
G01X218280Y73168D02*
X228976Y83428D01*
G01X218064Y73187D02*
X229024Y83701D01*
G01X229072Y83975D02*
X217848Y73209D01*
G01X223246Y78613D02*
X229120Y84248D01*
G01X217632Y73228D02*
X222314Y77720D01*
G01X223507Y79090D02*
X229168Y84521D01*
G01X217416Y73247D02*
X221853Y77504D01*
G01X217217Y73283D02*
X221529Y77421D01*
G01X223685Y79489D02*
X229216Y84795D01*
G01X217040Y73342D02*
X221217Y77348D01*
G01X223806Y79832D02*
X229264Y85069D01*
G01X229312Y85341D02*
X223918Y80167D01*
G01X216864Y73400D02*
X220962Y77331D01*
G01X216688Y73458D02*
X220708Y77314D01*
G01X229360Y85614D02*
X223983Y80456D01*
G01X216511Y73515D02*
X220469Y77312D01*
G01X229408Y85888D02*
X224049Y80747D01*
G01X216334Y73574D02*
X220247Y77327D01*
G01X229456Y86161D02*
X224114Y81037D01*
G01X216158Y73632D02*
X220026Y77343D01*
G01X216001Y73709D02*
X219825Y77376D01*
G01X215862Y73803D02*
X219639Y77425D01*
G01X215723Y73896D02*
X219453Y77474D01*
G01X215585Y73991D02*
X219290Y77545D01*
G01X215446Y74085D02*
X219142Y77630D01*
G01X215307Y74178D02*
X218993Y77715D01*
G01X215169Y74273D02*
X218869Y77823D01*
G01X215051Y74387D02*
X218760Y77946D01*
G01X214948Y74516D02*
X218652Y78068D01*
G01X214845Y74644D02*
X218561Y78208D01*
G01X214742Y74773D02*
X218491Y78369D01*
G01X214639Y74901D02*
X218421Y78529D01*
G01X214537Y75030D02*
X218358Y78695D01*
G01X214433Y75158D02*
X218325Y78892D01*
G01X214354Y75310D02*
X218292Y79088D01*
G01X214286Y75471D02*
X218260Y79283D01*
G01X214217Y75632D02*
X218252Y79503D01*
G01X214149Y75794D02*
X218254Y79732D01*
G01X214080Y75955D02*
X218256Y79961D01*
G01X214012Y76117D02*
X218258Y80190D01*
G01X213943Y76278D02*
X218292Y80450D01*
G01X213902Y76466D02*
X218325Y80709D01*
G01X213867Y76660D02*
X218359Y80969D01*
G01X213833Y76854D02*
X218393Y81229D01*
G01X213797Y77047D02*
X218441Y81501D01*
G01X213763Y77241D02*
X218489Y81775D01*
G01X213728Y77435D02*
X218536Y82048D01*
G01X213694Y77629D02*
X218585Y82321D01*
G01X213692Y77855D02*
X218633Y82595D01*
G01X213690Y78081D02*
X218681Y82868D01*
G01X213688Y78306D02*
X218728Y83141D01*
G01X213687Y78532D02*
X218776Y83414D01*
G01X213685Y78757D02*
X218825Y83687D01*
G01X213683Y78983D02*
X218872Y83960D01*
G01X218920Y84234D02*
X213691Y79218D01*
G01X218968Y84507D02*
X213723Y79475D01*
G01X219017Y84780D02*
X213754Y79732D01*
G01X219064Y85054D02*
X213785Y79989D01*
G01X219112Y85327D02*
X213816Y80247D01*
G01X219160Y85600D02*
X213848Y80504D01*
G01X219208Y85873D02*
X213879Y80761D01*
G01X219256Y86146D02*
X213922Y81029D01*
G01X240563Y78866D02*
X240516Y78593D01*
G01X240803Y80232D02*
X240755Y79959D01*
G01X240851Y80506D02*
X240803Y80232D01*
G01X240707Y79686D02*
X240659Y79413D01*
G01D02*
X240611Y79139D01*
G01X240755Y79959D02*
X240707Y79686D01*
G01X240611Y79139D02*
X240563Y78866D01*
G01X241813Y73476D02*
X242050D01*
G01X242287D02*
X242523D01*
G01D02*
X242760D01*
G01X242050D02*
X242287D01*
G01X241577D02*
X241813D01*
G01X242760D02*
X242997D01*
G01X241340D02*
X241577D01*
G01X240155D02*
X240392D01*
G01X239918D02*
X240155D01*
G01X239648Y73671D02*
X239614Y73476D01*
X239682D01*
G01D02*
X239918D01*
G01X239697Y73945D02*
X239648Y73671D01*
G01X241102Y73476D02*
X241340D01*
G01X240628D02*
X240865D01*
G01X240392D02*
X240628D01*
G01X240865D02*
X241102D01*
G01X239794Y74492D02*
X239745Y74219D01*
G01D02*
X239697Y73945D01*
G01X228303Y79602D02*
X228352Y79876D01*
G01X226891Y73476D02*
X227128D01*
G01X225943D02*
X226181D01*
G01D02*
X226417D01*
G01X225470D02*
X225707D01*
G01D02*
X225943D01*
G01X226654D02*
X226891D01*
G01X226417D02*
X226654D01*
G01X225233D02*
X225470D01*
G01X223102D02*
X223339D01*
G01X224997D02*
X225233D01*
G01X223575D02*
X223812D01*
G01D02*
X224049D01*
G01X223339D02*
X223575D01*
G01X224759D02*
X224997D01*
G01X222864D02*
X223102D01*
G01X224523D02*
X224759D01*
G01X224286D02*
X224523D01*
G01X224049D02*
X224286D01*
G01X222966Y74482D02*
X222917Y74208D01*
G01X222870Y73936D02*
X222822Y73662D01*
G01X222917Y74208D02*
X222870Y73936D01*
G01X222822Y73662D02*
X222790Y73476D01*
X222864D01*
G01X227391Y74410D02*
X227343Y74137D01*
G01D02*
X227296Y73864D01*
G01X227439Y74683D02*
X227391Y74410D01*
G01X227296Y73864D02*
X227247Y73590D01*
G01X227128Y73476D02*
X227227D01*
X227247Y73590D01*
G01X227631Y75776D02*
X227583Y75503D01*
G01D02*
X227536Y75230D01*
G01D02*
X227488Y74957D01*
G01D02*
X227439Y74683D01*
G01X227679Y76050D02*
X227631Y75776D01*
G01X228400Y80148D02*
X228448Y80422D01*
G01X228208Y79056D02*
X228256Y79329D01*
G01D02*
X228303Y79602D01*
G01X228352Y79876D02*
X228400Y80148D01*
G01X228448Y80422D02*
X228496Y80696D01*
G01D02*
X228543Y80969D01*
G01D02*
X228592Y81242D01*
G01X227823Y76869D02*
X227776Y76596D01*
G01X227920Y77416D02*
X227871Y77143D01*
G01D02*
X227823Y76869D01*
G01X227728Y76324D02*
X227679Y76050D01*
G01X227776Y76596D02*
X227728Y76324D01*
G01X227968Y77689D02*
X227920Y77416D01*
G01X228111Y78509D02*
X228063Y78236D01*
G01X228111Y78509D02*
X228160Y78783D01*
G01X228016Y77963D02*
X227968Y77689D01*
G01X228063Y78236D02*
X228016Y77963D01*
G01X228160Y78783D02*
X228208Y79056D01*
G01X213970Y81303D02*
X213922Y81029D01*
G01X242760Y73476D02*
X244316Y74969D01*
G01X242523Y73476D02*
X244365Y75242D01*
G01X242287Y73476D02*
X244411Y75514D01*
G01X242050Y73476D02*
X244460Y75788D01*
G01X241813Y73476D02*
X244509Y76061D01*
G01X241577Y73476D02*
X244555Y76334D01*
G01X241340Y73476D02*
X244604Y76607D01*
G01X241102Y73476D02*
X244651Y76880D01*
G01X240865Y73476D02*
X244699Y77154D01*
G01X240628Y73476D02*
X244748Y77427D01*
G01X240392Y73476D02*
X244795Y77700D01*
G01X240155Y73476D02*
X244843Y77974D01*
G01X239918Y73476D02*
X244891Y78247D01*
G01X239682Y73476D02*
X244939Y78519D01*
G01X239648Y73671D02*
X244986Y78793D01*
G01X239697Y73945D02*
X245035Y79066D01*
G01X239745Y74219D02*
X245083Y79339D01*
G01X239794Y74492D02*
X245130Y79612D01*
G01X239247Y74195D02*
X245179Y79885D01*
G01X238650Y73850D02*
X245226Y80159D01*
G01X238176Y73622D02*
X245274Y80432D01*
G01X237795Y73484D02*
X245323Y80705D01*
G01X237458Y73388D02*
X245370Y80978D01*
G01X237121Y73293D02*
X245418Y81251D01*
G01X236814Y73225D02*
X245466Y81524D01*
G01X236551Y73201D02*
X245514Y81798D01*
G01X236287Y73173D02*
X245561Y82070D01*
G01X236024Y73149D02*
X245610Y82344D01*
G01X235760Y73122D02*
X245658Y82618D01*
G01X235533Y73131D02*
X245705Y82890D01*
G01X235305Y73141D02*
X245754Y83163D01*
G01X245802Y83437D02*
X235084Y73156D01*
G01X234873Y73182D02*
X239431Y77553D01*
G01X245849Y83710D02*
X240516Y78593D01*
G01X234663Y73206D02*
X238910Y77280D01*
G01X245898Y83983D02*
X240563Y78866D01*
G01X234463Y73241D02*
X238528Y77141D01*
G01X245945Y84256D02*
X240611Y79139D01*
G01X245993Y84529D02*
X240659Y79413D01*
G01X234268Y73282D02*
X238154Y77010D01*
G01X234073Y73321D02*
X237883Y76977D01*
G01X246040Y84803D02*
X240707Y79686D01*
G01X233890Y73374D02*
X237612Y76943D01*
G01X246061Y85049D02*
X240755Y79959D01*
G01X233710Y73428D02*
X237341Y76910D01*
G01X246081Y85295D02*
X240803Y80232D01*
G01X233529Y73483D02*
X237080Y76888D01*
G01X246101Y85542D02*
X240851Y80506D01*
G01X246120Y85788D02*
X240741Y80628D01*
G01X233361Y73548D02*
X236860Y76904D01*
G01X233195Y73616D02*
X236640Y76920D01*
G01X246141Y86034D02*
X240601Y80719D01*
G01X246134Y86255D02*
X240449Y80801D01*
G01X233029Y73683D02*
X236430Y76945D01*
G01X232874Y73762D02*
X236243Y76994D01*
G01X246107Y86456D02*
X240293Y80880D01*
G01X246080Y86657D02*
X240129Y80949D01*
G01X232722Y73843D02*
X236057Y77043D01*
G01X246052Y86858D02*
X239957Y81011D01*
G01X232570Y73925D02*
X235886Y77106D01*
G01X232427Y74015D02*
X235733Y77186D01*
G01X246024Y87058D02*
X239778Y81066D01*
G01X232289Y74109D02*
X235580Y77267D01*
G01X232151Y74204D02*
X235453Y77373D01*
G01X232020Y74306D02*
X235333Y77485D01*
G01X231896Y74414D02*
X235223Y77606D01*
G01X231772Y74522D02*
X235137Y77750D01*
G01X231652Y74635D02*
X235050Y77895D01*
G01X231542Y74757D02*
X234997Y78070D01*
G01X231433Y74879D02*
X234945Y78248D01*
G01X231325Y75002D02*
X234923Y78454D01*
G01X231231Y75140D02*
X234908Y78667D01*
G01X231137Y75277D02*
X234928Y78913D01*
G01X231043Y75414D02*
X234964Y79175D01*
G01X230963Y75564D02*
X235089Y79522D01*
G01X236278Y80890D02*
X240097Y84554D01*
G01X230885Y75717D02*
X235215Y79870D01*
G01X230808Y75870D02*
X239897Y84588D01*
G01X230741Y76033D02*
X239697Y84624D01*
G01X230682Y76203D02*
X239496Y84658D01*
G01X230622Y76373D02*
X239284Y84683D01*
G01X230571Y76551D02*
X239059Y84694D01*
G01X230530Y76739D02*
X238835Y84706D01*
G01X227128Y73476D02*
X227247Y73590D01*
G01X226891Y73476D02*
X227296Y73864D01*
G01X230490Y76928D02*
X238610Y84718D01*
G01X226654Y73476D02*
X227343Y74137D01*
G01X230455Y77122D02*
X238386Y84730D01*
G01X230437Y77331D02*
X238138Y84719D01*
G01X226417Y73476D02*
X227391Y74410D01*
G01X230418Y77541D02*
X237885Y84704D01*
G01X226181Y73476D02*
X227439Y74683D01*
G01X225943Y73476D02*
X227488Y74957D01*
G01X230404Y77755D02*
X237632Y84688D01*
G01X230410Y77987D02*
X237378Y84672D01*
G01X225707Y73476D02*
X227536Y75230D01*
G01X230415Y78220D02*
X237125Y84657D01*
G01X225470Y73476D02*
X227583Y75503D01*
G01X225233Y73476D02*
X227631Y75776D01*
G01X230427Y78458D02*
X236861Y84630D01*
G01X230459Y78717D02*
X236563Y84572D01*
G01X224997Y73476D02*
X227679Y76050D01*
G01X230493Y78976D02*
X236265Y84514D01*
G01X224759Y73476D02*
X227728Y76324D01*
G01X224523Y73476D02*
X227776Y76596D01*
G01X230545Y79253D02*
X235968Y84455D01*
G01X230632Y79564D02*
X235670Y84397D01*
G01X224286Y73476D02*
X227823Y76869D01*
G01X224049Y73476D02*
X227871Y77143D01*
G01X230719Y79874D02*
X235315Y84283D01*
G01X230807Y80186D02*
X234940Y84151D01*
G01X223812Y73476D02*
X227920Y77416D01*
G01X230916Y80518D02*
X234566Y84019D01*
G01X223575Y73476D02*
X227968Y77689D01*
G01X223339Y73476D02*
X228016Y77963D01*
G01X231154Y80973D02*
X234115Y83813D01*
G01X223102Y73476D02*
X228063Y78236D01*
G01X222864Y73476D02*
X228111Y78509D01*
G01X222822Y73662D02*
X228160Y78783D01*
G01X222870Y73936D02*
X228208Y79056D01*
G01X222917Y74208D02*
X228256Y79329D01*
G01X222966Y74482D02*
X228303Y79602D01*
G01X222462Y74225D02*
X228352Y79876D01*
G01X221857Y73872D02*
X228400Y80148D01*
G01X221387Y73649D02*
X228448Y80422D01*
G01X221000Y73504D02*
X228496Y80696D01*
G01X220667Y73412D02*
X228543Y80969D01*
G01X220333Y73320D02*
X228592Y81242D01*
G01X220010Y73237D02*
X228640Y81516D01*
G01X219748Y73213D02*
X228688Y81789D01*
G01X219486Y73188D02*
X228736Y82062D01*
G01X219224Y73165D02*
X228784Y82335D01*
G01X218962Y73141D02*
X228832Y82608D01*
G01X218712Y73127D02*
X228880Y82882D01*
G01X218496Y73148D02*
X228928Y83155D01*
G01X218280Y73168D02*
X228976Y83428D01*
G01X218064Y73187D02*
X229024Y83701D01*
G01X229072Y83975D02*
X217848Y73209D01*
G01X223246Y78613D02*
X229120Y84248D01*
G01X217632Y73228D02*
X222314Y77720D01*
G01X223507Y79090D02*
X229168Y84521D01*
G01X217416Y73247D02*
X221853Y77504D01*
G01X217217Y73283D02*
X221529Y77421D01*
G01X223685Y79489D02*
X229216Y84795D01*
G01X217040Y73342D02*
X221217Y77348D01*
G01X223806Y79832D02*
X229264Y85069D01*
G01X229312Y85341D02*
X223918Y80167D01*
G01X216864Y73400D02*
X220962Y77331D01*
G01X216688Y73458D02*
X220708Y77314D01*
G01X229360Y85614D02*
X223983Y80456D01*
G01X216511Y73515D02*
X220469Y77312D01*
G01X229408Y85888D02*
X224049Y80747D01*
G01X216334Y73574D02*
X220247Y77327D01*
G01X229456Y86161D02*
X224114Y81037D01*
G01X216158Y73632D02*
X220026Y77343D01*
G01X216001Y73709D02*
X219825Y77376D01*
G01X215862Y73803D02*
X219639Y77425D01*
G01X215723Y73896D02*
X219453Y77474D01*
G01X215585Y73991D02*
X219290Y77545D01*
G01X215446Y74085D02*
X219142Y77630D01*
G01X215307Y74178D02*
X218993Y77715D01*
G01X215169Y74273D02*
X218869Y77823D01*
G01X215051Y74387D02*
X218760Y77946D01*
G01X214948Y74516D02*
X218652Y78068D01*
G01X214845Y74644D02*
X218561Y78208D01*
G01X214742Y74773D02*
X218491Y78369D01*
G01X214639Y74901D02*
X218421Y78529D01*
G01X214537Y75030D02*
X218358Y78695D01*
G01X214433Y75158D02*
X218325Y78892D01*
G01X214354Y75310D02*
X218292Y79088D01*
G01X214286Y75471D02*
X218260Y79283D01*
G01X214217Y75632D02*
X218252Y79503D01*
G01X214149Y75794D02*
X218254Y79732D01*
G01X214080Y75955D02*
X218256Y79961D01*
G01X214012Y76117D02*
X218258Y80190D01*
G01X213943Y76278D02*
X218292Y80450D01*
G01X213902Y76466D02*
X218325Y80709D01*
G01X213867Y76660D02*
X218359Y80969D01*
G01X213833Y76854D02*
X218393Y81229D01*
G01X213797Y77047D02*
X218441Y81501D01*
G01X213763Y77241D02*
X218489Y81775D01*
G01X213728Y77435D02*
X218536Y82048D01*
G01X213694Y77629D02*
X218585Y82321D01*
G01X213692Y77855D02*
X218633Y82595D01*
G01X213690Y78081D02*
X218681Y82868D01*
G01X213688Y78306D02*
X218728Y83141D01*
G01X213687Y78532D02*
X218776Y83414D01*
G01X213685Y78757D02*
X218825Y83687D01*
G01X213683Y78983D02*
X218872Y83960D01*
G01X218920Y84234D02*
X213691Y79218D01*
G01X218968Y84507D02*
X213723Y79475D01*
G01X219017Y84780D02*
X213754Y79732D01*
G01X219064Y85054D02*
X213785Y79989D01*
G01X219112Y85327D02*
X213816Y80247D01*
G01X219160Y85600D02*
X213848Y80504D01*
G01X219208Y85873D02*
X213879Y80761D01*
G01X219256Y86146D02*
X213922Y81029D01*
G01X240563Y78866D02*
X240516Y78593D01*
G01X240803Y80232D02*
X240755Y79959D01*
G01X240851Y80506D02*
X240803Y80232D01*
G01X240707Y79686D02*
X240659Y79413D01*
G01D02*
X240611Y79139D01*
G01X240755Y79959D02*
X240707Y79686D01*
G01X240611Y79139D02*
X240563Y78866D01*
G01X241813Y73476D02*
X242050D01*
G01X242287D02*
X242523D01*
G01D02*
X242760D01*
G01X242050D02*
X242287D01*
G01X241577D02*
X241813D01*
G01X242760D02*
X242997D01*
G01X241340D02*
X241577D01*
G01X240155D02*
X240392D01*
G01X239918D02*
X240155D01*
G01X239648Y73671D02*
X239614Y73476D01*
X239682D01*
G01D02*
X239918D01*
G01X239697Y73945D02*
X239648Y73671D01*
G01X241102Y73476D02*
X241340D01*
G01X240628D02*
X240865D01*
G01X240392D02*
X240628D01*
G01X240865D02*
X241102D01*
G01X239794Y74492D02*
X239745Y74219D01*
G01D02*
X239697Y73945D01*
G01X228303Y79602D02*
X228352Y79876D01*
G01X226891Y73476D02*
X227128D01*
G01X225943D02*
X226181D01*
G01D02*
X226417D01*
G01X225470D02*
X225707D01*
G01D02*
X225943D01*
G01X226654D02*
X226891D01*
G01X226417D02*
X226654D01*
G01X225233D02*
X225470D01*
G01X223102D02*
X223339D01*
G01X224997D02*
X225233D01*
G01X223575D02*
X223812D01*
G01D02*
X224049D01*
G01X223339D02*
X223575D01*
G01X224759D02*
X224997D01*
G01X222864D02*
X223102D01*
G01X224523D02*
X224759D01*
G01X224286D02*
X224523D01*
G01X224049D02*
X224286D01*
G01X222966Y74482D02*
X222917Y74208D01*
G01X222870Y73936D02*
X222822Y73662D01*
G01X222917Y74208D02*
X222870Y73936D01*
G01X222822Y73662D02*
X222790Y73476D01*
X222864D01*
G01X227391Y74410D02*
X227343Y74137D01*
G01D02*
X227296Y73864D01*
G01X227439Y74683D02*
X227391Y74410D01*
G01X227296Y73864D02*
X227247Y73590D01*
G01X227128Y73476D02*
X227227D01*
X227247Y73590D01*
G01X227631Y75776D02*
X227583Y75503D01*
G01D02*
X227536Y75230D01*
G01D02*
X227488Y74957D01*
G01D02*
X227439Y74683D01*
G01X227679Y76050D02*
X227631Y75776D01*
G01X228400Y80148D02*
X228448Y80422D01*
G01X228208Y79056D02*
X228256Y79329D01*
G01D02*
X228303Y79602D01*
G01X228352Y79876D02*
X228400Y80148D01*
G01X228448Y80422D02*
X228496Y80696D01*
G01D02*
X228543Y80969D01*
G01D02*
X228592Y81242D01*
G01X227823Y76869D02*
X227776Y76596D01*
G01X227920Y77416D02*
X227871Y77143D01*
G01D02*
X227823Y76869D01*
G01X227728Y76324D02*
X227679Y76050D01*
G01X227776Y76596D02*
X227728Y76324D01*
G01X227968Y77689D02*
X227920Y77416D01*
G01X228111Y78509D02*
X228063Y78236D01*
G01X228111Y78509D02*
X228160Y78783D01*
G01X228016Y77963D02*
X227968Y77689D01*
G01X228063Y78236D02*
X228016Y77963D01*
G01X228160Y78783D02*
X228208Y79056D01*
G01X213970Y81303D02*
X213922Y81029D01*
G01X245997Y87259D02*
X239588Y81112D01*
G01X245941Y87435D02*
X239393Y81153D01*
G01X245876Y87597D02*
X239189Y81183D01*
G01X245808Y87760D02*
X238980Y81210D01*
G01X245740Y87923D02*
X238762Y81228D01*
G01X245674Y88086D02*
X238540Y81243D01*
G01X241315Y84131D02*
X238313Y81252D01*
G01X245608Y88249D02*
X241520Y84328D01*
G01X241156Y84206D02*
X238081Y81257D01*
G01X245525Y88397D02*
X241567Y84601D01*
G01X245423Y88527D02*
X241614Y84874D01*
G01X240997Y84280D02*
X237841Y81253D01*
G01X240826Y84345D02*
X237569Y81219D01*
G01X245323Y88657D02*
X241640Y85125D01*
G01X245221Y88787D02*
X241654Y85366D01*
G01X237296Y81185D02*
X240648Y84401D01*
G01X237024Y81151D02*
X240470Y84457D01*
G01X245119Y88917D02*
X241633Y85572D01*
G01X236743Y81109D02*
X240291Y84513D01*
G01X245019Y89047D02*
X241603Y85771D01*
G01X244916Y89178D02*
X241545Y85943D01*
G01X244784Y89277D02*
X241484Y86111D01*
G01X244653Y89378D02*
X241393Y86251D01*
G01X244520Y89478D02*
X241301Y86390D01*
G01X244387Y89578D02*
X241185Y86506D01*
G01X244254Y89678D02*
X241062Y86615D01*
G01X244122Y89778D02*
X240927Y86713D01*
G01X243980Y89868D02*
X240774Y86793D01*
G01X243817Y89940D02*
X240620Y86873D01*
G01X243654Y90012D02*
X240437Y86925D01*
G01X243493Y90084D02*
X240252Y86974D01*
G01X243331Y90155D02*
X240053Y87011D01*
G01X243169Y90227D02*
X239834Y87028D01*
G01X243007Y90299D02*
X239615Y87045D01*
G01X242826Y90352D02*
X239377Y87043D01*
G01X242634Y90396D02*
X239134Y87039D01*
G01X242443Y90440D02*
X238892Y87034D01*
G01X242252Y90484D02*
X238639Y87018D01*
G01X242061Y90528D02*
X238385Y87001D01*
G01X241869Y90571D02*
X238123Y86978D01*
G01X241678Y90615D02*
X237850Y86942D01*
G01X241457Y90630D02*
X237573Y86904D01*
G01X241237Y90645D02*
X237274Y86844D01*
G01X241015Y90660D02*
X236966Y86776D01*
G01X231392Y81429D02*
X233563Y83511D01*
G01X240794Y90676D02*
X236633Y86684D01*
G01X240573Y90691D02*
X236277Y86569D01*
G01X240352Y90705D02*
X235898Y86432D01*
G01X240120Y90711D02*
X235476Y86255D01*
G01X239876Y90704D02*
X235020Y86045D01*
G01X239632Y90697D02*
X234730Y85994D01*
G01X239389Y90691D02*
X234667Y86161D01*
G01X239137Y90677D02*
X234604Y86328D01*
G01X238876Y90653D02*
X234541Y86495D01*
G01X238615Y90630D02*
X234479Y86662D01*
G01X238355Y90607D02*
X234416Y86829D01*
G01X238071Y90563D02*
X234353Y86996D01*
G01X237787Y90518D02*
X234290Y87163D01*
G01X237503Y90472D02*
X234227Y87330D01*
G01X237191Y90400D02*
X234164Y87496D01*
G01X236877Y90327D02*
X234102Y87663D01*
G01X236549Y90239D02*
X234039Y87831D01*
G01X236199Y90130D02*
X233976Y87998D01*
G01X235840Y90012D02*
X233913Y88164D01*
G01X235445Y89861D02*
X233850Y88331D01*
G01X235036Y89696D02*
X233787Y88499D01*
G01X234592Y89498D02*
X233725Y88665D01*
G01X234121Y89272D02*
X233662Y88832D01*
G01X233624Y89023D02*
X233599Y88999D01*
G01X229504Y86434D02*
X224167Y81315D01*
G01X229552Y86707D02*
X224215Y81588D01*
G01X229600Y86981D02*
X224263Y81861D01*
G01X229648Y87254D02*
X224311Y82135D01*
G01X229696Y87528D02*
X224359Y82407D01*
G01X229744Y87800D02*
X224407Y82680D01*
G01X229792Y88074D02*
X224455Y82954D01*
G01X229840Y88347D02*
X224503Y83227D01*
G01X229888Y88621D02*
X224550Y83500D01*
G01X229936Y88893D02*
X224598Y83773D01*
G01X229985Y89167D02*
X224646Y84046D01*
G01X230033Y89441D02*
X224694Y84320D01*
G01X230080Y89714D02*
X224742Y84592D01*
G01X230128Y89987D02*
X224790Y84865D01*
G01X230176Y90260D02*
X224838Y85139D01*
G01X230044Y90361D02*
X224885Y85412D01*
G01X229808Y90361D02*
X224934Y85685D01*
G01X229571Y90361D02*
X224981Y85958D01*
G01X229334Y90361D02*
X225029Y86231D01*
G01X229097Y90361D02*
X225077Y86505D01*
G01X228860Y90361D02*
X225125Y86778D01*
G01X228623Y90361D02*
X225173Y87050D01*
G01X228387Y90361D02*
X225220Y87324D01*
G01X228149Y90361D02*
X225269Y87597D01*
G01X227913Y90361D02*
X225316Y87870D01*
G01X227676Y90361D02*
X225364Y88143D01*
G01X227439Y90361D02*
X225412Y88416D01*
G01X227202Y90361D02*
X225460Y88690D01*
G01X226965Y90361D02*
X225508Y88963D01*
G01X226729Y90361D02*
X225555Y89235D01*
G01X226492Y90361D02*
X225604Y89509D01*
G01X226255Y90361D02*
X225652Y89782D01*
G01X226018Y90361D02*
X225699Y90055D01*
G01X225781Y90361D02*
X225747Y90328D01*
G01X219304Y86419D02*
X213970Y81303D01*
G01X219352Y86693D02*
X214018Y81576D01*
G01X219400Y86966D02*
X214066Y81849D01*
G01X219448Y87239D02*
X214114Y82123D01*
G01X219496Y87513D02*
X214162Y82396D01*
G01X219544Y87785D02*
X214210Y82669D01*
G01X219592Y88059D02*
X214258Y82942D01*
G01X219640Y88332D02*
X214306Y83215D01*
G01X219688Y88606D02*
X214353Y83488D01*
G01X219735Y88878D02*
X214402Y83762D01*
G01X219784Y89151D02*
X214450Y84035D01*
G01X219832Y89425D02*
X214497Y84308D01*
G01X219879Y89698D02*
X214545Y84582D01*
G01X219927Y89972D02*
X214594Y84854D01*
G01X219975Y90244D02*
X214642Y85128D01*
G01X219860Y90361D02*
X214689Y85401D01*
G01X219623Y90361D02*
X214737Y85675D01*
G01X219386Y90361D02*
X214785Y85947D01*
G01X219149Y90361D02*
X214833Y86220D01*
G01X218912Y90361D02*
X214881Y86494D01*
G01X218675Y90361D02*
X214929Y86767D01*
G01X218439Y90361D02*
X214977Y87041D01*
G01X218202Y90361D02*
X215025Y87313D01*
G01X217965Y90361D02*
X215073Y87587D01*
G01X217728Y90361D02*
X215121Y87860D01*
G01X217491Y90361D02*
X215169Y88133D01*
G01X217255Y90361D02*
X215217Y88406D01*
G01X217017Y90361D02*
X215265Y88680D01*
G01X216781Y90361D02*
X215313Y88953D01*
G01X216544Y90361D02*
X215361Y89226D01*
G01X216307Y90361D02*
X215409Y89499D01*
G01X216070Y90361D02*
X215457Y89772D01*
G01X215833Y90361D02*
X215505Y90046D01*
G01X215597Y90361D02*
X215552Y90319D01*
G01X233787Y88499D02*
X233725Y88665D01*
G01X233787Y88499D02*
X233850Y88331D01*
G01X233725Y88665D02*
X233662Y88832D01*
G01D02*
X233599Y88999D01*
G01X233850Y88331D02*
X233913Y88164D01*
G01X234039Y87831D02*
X234102Y87663D01*
G01X233976Y87998D02*
X234039Y87831D01*
G01X233913Y88164D02*
X233976Y87998D01*
G01X234102Y87663D02*
X234164Y87496D01*
G01X234667Y86161D02*
X234730Y85994D01*
G01X234353Y86996D02*
X234416Y86829D01*
G01X234290Y87163D02*
X234353Y86996D01*
G01X234227Y87330D02*
X234290Y87163D01*
G01X234416Y86829D02*
X234479Y86662D01*
G01X234604Y86328D02*
X234667Y86161D01*
G01X234164Y87496D02*
X234227Y87330D01*
G01X234479Y86662D02*
X234541Y86495D01*
G01D02*
X234604Y86328D01*
G01X241567Y84601D02*
X241520Y84328D01*
G01X241614Y84874D02*
X241567Y84601D01*
G01X224934Y85685D02*
X224885Y85412D01*
G01X229168Y84521D02*
X229216Y84795D01*
G01X229120Y84248D02*
X229168Y84521D01*
G01X228688Y81789D02*
X228736Y82062D01*
G01X228784Y82335D02*
X228832Y82608D01*
G01X228736Y82062D02*
X228784Y82335D01*
G01X229072Y83975D02*
X229024Y83701D01*
G01X228880Y82882D02*
X228928Y83155D01*
G01X229024Y83701D02*
X228976Y83428D01*
G01X228928Y83155D02*
X228976Y83428D01*
G01X218585Y82321D02*
X218633Y82595D01*
G01X218441Y81501D02*
X218489Y81775D01*
G01X218633Y82595D02*
X218681Y82868D01*
G01X218393Y81229D02*
X218441Y81501D01*
G01X218536Y82048D02*
X218585Y82321D01*
G01X218776Y83414D02*
X218825Y83687D01*
G01X218728Y83141D02*
X218776Y83414D01*
G01X218681Y82868D02*
X218728Y83141D01*
G01X228832Y82608D02*
X228880Y82882D01*
G01X228623Y90361D02*
X228387D01*
G01X228860D02*
X228623D01*
G01X228149D02*
X227913D01*
G01D02*
X227676D01*
G01X229072Y83975D02*
X229120Y84248D01*
G01X229808Y90361D02*
X229571D01*
G01X229097D02*
X228860D01*
G01X229571D02*
X229334D01*
G01D02*
X229097D01*
G01X226729D02*
X226492D01*
G01D02*
X226255D01*
G01D02*
X226018D01*
G01X218872Y83960D02*
X218920Y84234D01*
G01X226018Y90361D02*
X225781D01*
G01X218920Y84234D02*
X218968Y84507D01*
G01X227439Y90361D02*
X227202D01*
G01X226965D02*
X226729D01*
G01X230044D02*
X229808D01*
G01X227202D02*
X226965D01*
G01X227676D02*
X227439D01*
G01X229504Y86434D02*
X229552Y86707D01*
G01X229456Y86161D02*
X229504Y86434D01*
G01X229648Y87254D02*
X229696Y87528D01*
G01X230176Y90260D02*
X230194Y90361D01*
X230044D01*
G01X229600Y86981D02*
X229648Y87254D01*
G01X229264Y85069D02*
X229312Y85341D01*
G01X229360Y85614D02*
X229408Y85888D01*
G01D02*
X229456Y86161D01*
G01X229312Y85341D02*
X229360Y85614D01*
G01X229552Y86707D02*
X229600Y86981D01*
G01X229985Y89167D02*
X230033Y89441D01*
G01D02*
X230080Y89714D01*
G01X229696Y87528D02*
X229744Y87800D01*
G01X230080Y89714D02*
X230128Y89987D01*
G01D02*
X230176Y90260D01*
G01X229792Y88074D02*
X229840Y88347D01*
G01X229744Y87800D02*
X229792Y88074D01*
G01X229936Y88893D02*
X229985Y89167D01*
G01X229888Y88621D02*
X229936Y88893D01*
G01X229840Y88347D02*
X229888Y88621D01*
G01X228387Y90361D02*
X228149D01*
G01X218912D02*
X218675D01*
G01D02*
X218439D01*
G01X217965D02*
X217728D01*
G01X218439D02*
X218202D01*
G01D02*
X217965D01*
G01X219860D02*
X219623D01*
G01D02*
X219386D01*
G01X219149D02*
X218912D01*
G01X219386D02*
X219149D01*
G01X219975Y90244D02*
X219996Y90361D01*
X219860D01*
G01X216070D02*
X215833D01*
G01X217728D02*
X217491D01*
G01X215833D02*
X215597D01*
G01X216307D02*
X216070D01*
G01X217491D02*
X217255D01*
G01D02*
X217017D01*
G01D02*
X216781D01*
G01X216544D02*
X216307D01*
G01X216781D02*
X216544D01*
G01X219256Y86146D02*
X219304Y86419D01*
G01X218968Y84507D02*
X219017Y84780D01*
G01X219352Y86693D02*
X219400Y86966D01*
G01X219208Y85873D02*
X219256Y86146D01*
G01X219304Y86419D02*
X219352Y86693D01*
G01X219160Y85600D02*
X219208Y85873D01*
G01X219017Y84780D02*
X219064Y85054D01*
G01X219927Y89972D02*
X219975Y90244D01*
G01X219112Y85327D02*
X219160Y85600D01*
G01X219400Y86966D02*
X219448Y87239D01*
G01X219064Y85054D02*
X219112Y85327D01*
G01X219784Y89151D02*
X219832Y89425D01*
G01X219735Y88878D02*
X219784Y89151D01*
G01X219879Y89698D02*
X219927Y89972D01*
G01X219832Y89425D02*
X219879Y89698D01*
G01X219544Y87785D02*
X219592Y88059D01*
G01X219448Y87239D02*
X219496Y87513D01*
G01D02*
X219544Y87785D01*
G01X219640Y88332D02*
X219688Y88606D01*
G01D02*
X219735Y88878D01*
G01X219592Y88059D02*
X219640Y88332D01*
G01X218489Y81775D02*
X218536Y82048D01*
G01X215313Y88953D02*
X215361Y89226D01*
G01X215409Y89499D02*
X215457Y89772D01*
G01X215361Y89226D02*
X215409Y89499D01*
G01X215265Y88680D02*
X215313Y88953D01*
G01X215457Y89772D02*
X215505Y90046D01*
G01X215121Y87860D02*
X215073Y87587D01*
G01X215217Y88406D02*
X215265Y88680D01*
G01X215169Y88133D02*
X215217Y88406D01*
G01X215121Y87860D02*
X215169Y88133D01*
G01X215597Y90361D02*
X215560D01*
X215552Y90319D01*
G01X215073Y87587D02*
X215025Y87313D01*
G01X215505Y90046D02*
X215552Y90319D01*
G01X214210Y82669D02*
X214162Y82396D01*
G01X214353Y83488D02*
X214306Y83215D01*
G01D02*
X214258Y82942D01*
G01X214497Y84308D02*
X214450Y84035D01*
G01D02*
X214402Y83762D01*
G01D02*
X214353Y83488D01*
G01X214258Y82942D02*
X214210Y82669D01*
G01X215025Y87313D02*
X214977Y87041D01*
G01X214162Y82396D02*
X214114Y82123D01*
G01D02*
X214066Y81849D01*
G01X214881Y86494D02*
X214833Y86220D01*
G01X214545Y84582D02*
X214497Y84308D01*
G01X214833Y86220D02*
X214785Y85947D01*
G01X214977Y87041D02*
X214929Y86767D01*
G01D02*
X214881Y86494D01*
G01X214785Y85947D02*
X214737Y85675D01*
G01X214594Y84854D02*
X214545Y84582D01*
G01X214642Y85128D02*
X214594Y84854D01*
G01X214737Y85675D02*
X214689Y85401D01*
G01D02*
X214642Y85128D01*
G01X228640Y81516D02*
X228688Y81789D01*
G01X214066Y81849D02*
X214018Y81576D01*
G01X224263Y81861D02*
X224215Y81588D01*
G01X229264Y85069D02*
X229216Y84795D01*
G01X224215Y81588D02*
X224167Y81315D01*
G01X224311Y82135D02*
X224263Y81861D01*
G01X228592Y81242D02*
X228640Y81516D01*
G01X224742Y84592D02*
X224694Y84320D01*
G01X224359Y82407D02*
X224311Y82135D01*
G01X225699Y90055D02*
X225747Y90328D01*
G01X225604Y89509D02*
X225652Y89782D01*
G01X225781Y90361D02*
X225753D01*
X225747Y90328D01*
G01X225412Y88416D02*
X225460Y88690D01*
G01X218872Y83960D02*
X218825Y83687D01*
G01X225508Y88963D02*
X225555Y89235D01*
G01D02*
X225604Y89509D01*
G01X225460Y88690D02*
X225508Y88963D01*
G01X225364Y88143D02*
X225412Y88416D01*
G01X225652Y89782D02*
X225699Y90055D01*
G01X224694Y84320D02*
X224646Y84046D01*
G01X224838Y85139D02*
X224790Y84865D01*
G01X214018Y81576D02*
X213970Y81303D01*
G01X224646Y84046D02*
X224598Y83773D01*
G01X224790Y84865D02*
X224742Y84592D01*
G01X224455Y82954D02*
X224407Y82680D01*
G01D02*
X224359Y82407D01*
G01X224598Y83773D02*
X224550Y83500D01*
G01X224503Y83227D02*
X224455Y82954D01*
G01X224550Y83500D02*
X224503Y83227D01*
G01X225316Y87870D02*
X225364Y88143D01*
G01X225173Y87050D02*
X225125Y86778D01*
G01X225220Y87324D02*
X225173Y87050D01*
G01X225269Y87597D02*
X225316Y87870D01*
G01X225269Y87597D02*
X225220Y87324D01*
G01X225077Y86505D02*
X225029Y86231D01*
G01X224885Y85412D02*
X224838Y85139D01*
G01X224981Y85958D02*
X224934Y85685D01*
G01X225029Y86231D02*
X224981Y85958D01*
G01X225125Y86778D02*
X225077Y86505D01*
G01X245997Y87259D02*
X239588Y81112D01*
G01X245941Y87435D02*
X239393Y81153D01*
G01X245876Y87597D02*
X239189Y81183D01*
G01X245808Y87760D02*
X238980Y81210D01*
G01X245740Y87923D02*
X238762Y81228D01*
G01X245674Y88086D02*
X238540Y81243D01*
G01X241315Y84131D02*
X238313Y81252D01*
G01X245608Y88249D02*
X241520Y84328D01*
G01X241156Y84206D02*
X238081Y81257D01*
G01X245525Y88397D02*
X241567Y84601D01*
G01X245423Y88527D02*
X241614Y84874D01*
G01X240997Y84280D02*
X237841Y81253D01*
G01X240826Y84345D02*
X237569Y81219D01*
G01X245323Y88657D02*
X241640Y85125D01*
G01X245221Y88787D02*
X241654Y85366D01*
G01X237296Y81185D02*
X240648Y84401D01*
G01X237024Y81151D02*
X240470Y84457D01*
G01X245119Y88917D02*
X241633Y85572D01*
G01X236743Y81109D02*
X240291Y84513D01*
G01X245019Y89047D02*
X241603Y85771D01*
G01X244916Y89178D02*
X241545Y85943D01*
G01X244784Y89277D02*
X241484Y86111D01*
G01X244653Y89378D02*
X241393Y86251D01*
G01X244520Y89478D02*
X241301Y86390D01*
G01X244387Y89578D02*
X241185Y86506D01*
G01X244254Y89678D02*
X241062Y86615D01*
G01X244122Y89778D02*
X240927Y86713D01*
G01X243980Y89868D02*
X240774Y86793D01*
G01X243817Y89940D02*
X240620Y86873D01*
G01X243654Y90012D02*
X240437Y86925D01*
G01X243493Y90084D02*
X240252Y86974D01*
G01X243331Y90155D02*
X240053Y87011D01*
G01X243169Y90227D02*
X239834Y87028D01*
G01X243007Y90299D02*
X239615Y87045D01*
G01X242826Y90352D02*
X239377Y87043D01*
G01X242634Y90396D02*
X239134Y87039D01*
G01X242443Y90440D02*
X238892Y87034D01*
G01X242252Y90484D02*
X238639Y87018D01*
G01X242061Y90528D02*
X238385Y87001D01*
G01X241869Y90571D02*
X238123Y86978D01*
G01X241678Y90615D02*
X237850Y86942D01*
G01X241457Y90630D02*
X237573Y86904D01*
G01X241237Y90645D02*
X237274Y86844D01*
G01X241015Y90660D02*
X236966Y86776D01*
G01X231392Y81429D02*
X233563Y83511D01*
G01X240794Y90676D02*
X236633Y86684D01*
G01X240573Y90691D02*
X236277Y86569D01*
G01X240352Y90705D02*
X235898Y86432D01*
G01X240120Y90711D02*
X235476Y86255D01*
G01X239876Y90704D02*
X235020Y86045D01*
G01X239632Y90697D02*
X234730Y85994D01*
G01X239389Y90691D02*
X234667Y86161D01*
G01X239137Y90677D02*
X234604Y86328D01*
G01X238876Y90653D02*
X234541Y86495D01*
G01X238615Y90630D02*
X234479Y86662D01*
G01X238355Y90607D02*
X234416Y86829D01*
G01X238071Y90563D02*
X234353Y86996D01*
G01X237787Y90518D02*
X234290Y87163D01*
G01X237503Y90472D02*
X234227Y87330D01*
G01X237191Y90400D02*
X234164Y87496D01*
G01X236877Y90327D02*
X234102Y87663D01*
G01X236549Y90239D02*
X234039Y87831D01*
G01X236199Y90130D02*
X233976Y87998D01*
G01X235840Y90012D02*
X233913Y88164D01*
G01X235445Y89861D02*
X233850Y88331D01*
G01X235036Y89696D02*
X233787Y88499D01*
G01X234592Y89498D02*
X233725Y88665D01*
G01X234121Y89272D02*
X233662Y88832D01*
G01X233624Y89023D02*
X233599Y88999D01*
G01X229504Y86434D02*
X224167Y81315D01*
G01X229552Y86707D02*
X224215Y81588D01*
G01X229600Y86981D02*
X224263Y81861D01*
G01X229648Y87254D02*
X224311Y82135D01*
G01X229696Y87528D02*
X224359Y82407D01*
G01X229744Y87800D02*
X224407Y82680D01*
G01X229792Y88074D02*
X224455Y82954D01*
G01X229840Y88347D02*
X224503Y83227D01*
G01X229888Y88621D02*
X224550Y83500D01*
G01X229936Y88893D02*
X224598Y83773D01*
G01X229985Y89167D02*
X224646Y84046D01*
G01X230033Y89441D02*
X224694Y84320D01*
G01X230080Y89714D02*
X224742Y84592D01*
G01X230128Y89987D02*
X224790Y84865D01*
G01X230176Y90260D02*
X224838Y85139D01*
G01X230044Y90361D02*
X224885Y85412D01*
G01X229808Y90361D02*
X224934Y85685D01*
G01X229571Y90361D02*
X224981Y85958D01*
G01X229334Y90361D02*
X225029Y86231D01*
G01X229097Y90361D02*
X225077Y86505D01*
G01X228860Y90361D02*
X225125Y86778D01*
G01X228623Y90361D02*
X225173Y87050D01*
G01X228387Y90361D02*
X225220Y87324D01*
G01X228149Y90361D02*
X225269Y87597D01*
G01X227913Y90361D02*
X225316Y87870D01*
G01X227676Y90361D02*
X225364Y88143D01*
G01X227439Y90361D02*
X225412Y88416D01*
G01X227202Y90361D02*
X225460Y88690D01*
G01X226965Y90361D02*
X225508Y88963D01*
G01X226729Y90361D02*
X225555Y89235D01*
G01X226492Y90361D02*
X225604Y89509D01*
G01X226255Y90361D02*
X225652Y89782D01*
G01X226018Y90361D02*
X225699Y90055D01*
G01X225781Y90361D02*
X225747Y90328D01*
G01X219304Y86419D02*
X213970Y81303D01*
G01X219352Y86693D02*
X214018Y81576D01*
G01X219400Y86966D02*
X214066Y81849D01*
G01X219448Y87239D02*
X214114Y82123D01*
G01X219496Y87513D02*
X214162Y82396D01*
G01X219544Y87785D02*
X214210Y82669D01*
G01X219592Y88059D02*
X214258Y82942D01*
G01X219640Y88332D02*
X214306Y83215D01*
G01X219688Y88606D02*
X214353Y83488D01*
G01X219735Y88878D02*
X214402Y83762D01*
G01X219784Y89151D02*
X214450Y84035D01*
G01X219832Y89425D02*
X214497Y84308D01*
G01X219879Y89698D02*
X214545Y84582D01*
G01X219927Y89972D02*
X214594Y84854D01*
G01X219975Y90244D02*
X214642Y85128D01*
G01X219860Y90361D02*
X214689Y85401D01*
G01X219623Y90361D02*
X214737Y85675D01*
G01X219386Y90361D02*
X214785Y85947D01*
G01X219149Y90361D02*
X214833Y86220D01*
G01X218912Y90361D02*
X214881Y86494D01*
G01X218675Y90361D02*
X214929Y86767D01*
G01X218439Y90361D02*
X214977Y87041D01*
G01X218202Y90361D02*
X215025Y87313D01*
G01X217965Y90361D02*
X215073Y87587D01*
G01X217728Y90361D02*
X215121Y87860D01*
G01X217491Y90361D02*
X215169Y88133D01*
G01X217255Y90361D02*
X215217Y88406D01*
G01X217017Y90361D02*
X215265Y88680D01*
G01X216781Y90361D02*
X215313Y88953D01*
G01X216544Y90361D02*
X215361Y89226D01*
G01X216307Y90361D02*
X215409Y89499D01*
G01X216070Y90361D02*
X215457Y89772D01*
G01X215833Y90361D02*
X215505Y90046D01*
G01X215597Y90361D02*
X215552Y90319D01*
G01X233787Y88499D02*
X233725Y88665D01*
G01X233787Y88499D02*
X233850Y88331D01*
G01X233725Y88665D02*
X233662Y88832D01*
G01D02*
X233599Y88999D01*
G01X233850Y88331D02*
X233913Y88164D01*
G01X234039Y87831D02*
X234102Y87663D01*
G01X233976Y87998D02*
X234039Y87831D01*
G01X233913Y88164D02*
X233976Y87998D01*
G01X234102Y87663D02*
X234164Y87496D01*
G01X234667Y86161D02*
X234730Y85994D01*
G01X234353Y86996D02*
X234416Y86829D01*
G01X234290Y87163D02*
X234353Y86996D01*
G01X234227Y87330D02*
X234290Y87163D01*
G01X234416Y86829D02*
X234479Y86662D01*
G01X234604Y86328D02*
X234667Y86161D01*
G01X234164Y87496D02*
X234227Y87330D01*
G01X234479Y86662D02*
X234541Y86495D01*
G01D02*
X234604Y86328D01*
G01X241567Y84601D02*
X241520Y84328D01*
G01X241614Y84874D02*
X241567Y84601D01*
G01X224934Y85685D02*
X224885Y85412D01*
G01X229168Y84521D02*
X229216Y84795D01*
G01X229120Y84248D02*
X229168Y84521D01*
G01X228688Y81789D02*
X228736Y82062D01*
G01X228784Y82335D02*
X228832Y82608D01*
G01X228736Y82062D02*
X228784Y82335D01*
G01X229072Y83975D02*
X229024Y83701D01*
G01X228880Y82882D02*
X228928Y83155D01*
G01X229024Y83701D02*
X228976Y83428D01*
G01X228928Y83155D02*
X228976Y83428D01*
G01X218585Y82321D02*
X218633Y82595D01*
G01X218441Y81501D02*
X218489Y81775D01*
G01X218633Y82595D02*
X218681Y82868D01*
G01X218393Y81229D02*
X218441Y81501D01*
G01X218536Y82048D02*
X218585Y82321D01*
G01X218776Y83414D02*
X218825Y83687D01*
G01X218728Y83141D02*
X218776Y83414D01*
G01X218681Y82868D02*
X218728Y83141D01*
G01X228832Y82608D02*
X228880Y82882D01*
G01X228623Y90361D02*
X228387D01*
G01X228860D02*
X228623D01*
G01X228149D02*
X227913D01*
G01D02*
X227676D01*
G01X229072Y83975D02*
X229120Y84248D01*
G01X229808Y90361D02*
X229571D01*
G01X229097D02*
X228860D01*
G01X229571D02*
X229334D01*
G01D02*
X229097D01*
G01X226729D02*
X226492D01*
G01D02*
X226255D01*
G01D02*
X226018D01*
G01X218872Y83960D02*
X218920Y84234D01*
G01X226018Y90361D02*
X225781D01*
G01X218920Y84234D02*
X218968Y84507D01*
G01X227439Y90361D02*
X227202D01*
G01X226965D02*
X226729D01*
G01X230044D02*
X229808D01*
G01X227202D02*
X226965D01*
G01X227676D02*
X227439D01*
G01X229504Y86434D02*
X229552Y86707D01*
G01X229456Y86161D02*
X229504Y86434D01*
G01X229648Y87254D02*
X229696Y87528D01*
G01X230176Y90260D02*
X230194Y90361D01*
X230044D01*
G01X229600Y86981D02*
X229648Y87254D01*
G01X229264Y85069D02*
X229312Y85341D01*
G01X229360Y85614D02*
X229408Y85888D01*
G01D02*
X229456Y86161D01*
G01X229312Y85341D02*
X229360Y85614D01*
G01X229552Y86707D02*
X229600Y86981D01*
G01X229985Y89167D02*
X230033Y89441D01*
G01D02*
X230080Y89714D01*
G01X229696Y87528D02*
X229744Y87800D01*
G01X230080Y89714D02*
X230128Y89987D01*
G01D02*
X230176Y90260D01*
G01X229792Y88074D02*
X229840Y88347D01*
G01X229744Y87800D02*
X229792Y88074D01*
G01X229936Y88893D02*
X229985Y89167D01*
G01X229888Y88621D02*
X229936Y88893D01*
G01X229840Y88347D02*
X229888Y88621D01*
G01X228387Y90361D02*
X228149D01*
G01X218912D02*
X218675D01*
G01D02*
X218439D01*
G01X217965D02*
X217728D01*
G01X218439D02*
X218202D01*
G01D02*
X217965D01*
G01X219860D02*
X219623D01*
G01D02*
X219386D01*
G01X219149D02*
X218912D01*
G01X219386D02*
X219149D01*
G01X219975Y90244D02*
X219996Y90361D01*
X219860D01*
G01X216070D02*
X215833D01*
G01X217728D02*
X217491D01*
G01X215833D02*
X215597D01*
G01X216307D02*
X216070D01*
G01X217491D02*
X217255D01*
G01D02*
X217017D01*
G01D02*
X216781D01*
G01X216544D02*
X216307D01*
G01X216781D02*
X216544D01*
G01X219256Y86146D02*
X219304Y86419D01*
G01X218968Y84507D02*
X219017Y84780D01*
G01X219352Y86693D02*
X219400Y86966D01*
G01X219208Y85873D02*
X219256Y86146D01*
G01X219304Y86419D02*
X219352Y86693D01*
G01X219160Y85600D02*
X219208Y85873D01*
G01X219017Y84780D02*
X219064Y85054D01*
G01X219927Y89972D02*
X219975Y90244D01*
G01X219112Y85327D02*
X219160Y85600D01*
G01X219400Y86966D02*
X219448Y87239D01*
G01X219064Y85054D02*
X219112Y85327D01*
G01X219784Y89151D02*
X219832Y89425D01*
G01X219735Y88878D02*
X219784Y89151D01*
G01X219879Y89698D02*
X219927Y89972D01*
G01X219832Y89425D02*
X219879Y89698D01*
G01X219544Y87785D02*
X219592Y88059D01*
G01X219448Y87239D02*
X219496Y87513D01*
G01D02*
X219544Y87785D01*
G01X219640Y88332D02*
X219688Y88606D01*
G01D02*
X219735Y88878D01*
G01X219592Y88059D02*
X219640Y88332D01*
G01X218489Y81775D02*
X218536Y82048D01*
G01X215313Y88953D02*
X215361Y89226D01*
G01X215409Y89499D02*
X215457Y89772D01*
G01X215361Y89226D02*
X215409Y89499D01*
G01X215265Y88680D02*
X215313Y88953D01*
G01X215457Y89772D02*
X215505Y90046D01*
G01X215121Y87860D02*
X215073Y87587D01*
G01X215217Y88406D02*
X215265Y88680D01*
G01X215169Y88133D02*
X215217Y88406D01*
G01X215121Y87860D02*
X215169Y88133D01*
G01X215597Y90361D02*
X215560D01*
X215552Y90319D01*
G01X215073Y87587D02*
X215025Y87313D01*
G01X215505Y90046D02*
X215552Y90319D01*
G01X214210Y82669D02*
X214162Y82396D01*
G01X214353Y83488D02*
X214306Y83215D01*
G01D02*
X214258Y82942D01*
G01X214497Y84308D02*
X214450Y84035D01*
G01D02*
X214402Y83762D01*
G01D02*
X214353Y83488D01*
G01X214258Y82942D02*
X214210Y82669D01*
G01X215025Y87313D02*
X214977Y87041D01*
G01X214162Y82396D02*
X214114Y82123D01*
G01D02*
X214066Y81849D01*
G01X214881Y86494D02*
X214833Y86220D01*
G01X214545Y84582D02*
X214497Y84308D01*
G01X214833Y86220D02*
X214785Y85947D01*
G01X214977Y87041D02*
X214929Y86767D01*
G01D02*
X214881Y86494D01*
G01X214785Y85947D02*
X214737Y85675D01*
G01X214594Y84854D02*
X214545Y84582D01*
G01X214642Y85128D02*
X214594Y84854D01*
G01X214737Y85675D02*
X214689Y85401D01*
G01D02*
X214642Y85128D01*
G01X228640Y81516D02*
X228688Y81789D01*
G01X214066Y81849D02*
X214018Y81576D01*
G01X224263Y81861D02*
X224215Y81588D01*
G01X229264Y85069D02*
X229216Y84795D01*
G01X224215Y81588D02*
X224167Y81315D01*
G01X224311Y82135D02*
X224263Y81861D01*
G01X228592Y81242D02*
X228640Y81516D01*
G01X224742Y84592D02*
X224694Y84320D01*
G01X224359Y82407D02*
X224311Y82135D01*
G01X225699Y90055D02*
X225747Y90328D01*
G01X225604Y89509D02*
X225652Y89782D01*
G01X225781Y90361D02*
X225753D01*
X225747Y90328D01*
G01X225412Y88416D02*
X225460Y88690D01*
G01X218872Y83960D02*
X218825Y83687D01*
G01X225508Y88963D02*
X225555Y89235D01*
G01D02*
X225604Y89509D01*
G01X225460Y88690D02*
X225508Y88963D01*
G01X225364Y88143D02*
X225412Y88416D01*
G01X225652Y89782D02*
X225699Y90055D01*
G01X224694Y84320D02*
X224646Y84046D01*
G01X224838Y85139D02*
X224790Y84865D01*
G01X214018Y81576D02*
X213970Y81303D01*
G01X224646Y84046D02*
X224598Y83773D01*
G01X224790Y84865D02*
X224742Y84592D01*
G01X224455Y82954D02*
X224407Y82680D01*
G01D02*
X224359Y82407D01*
G01X224598Y83773D02*
X224550Y83500D01*
G01X224503Y83227D02*
X224455Y82954D01*
G01X224550Y83500D02*
X224503Y83227D01*
G01X225316Y87870D02*
X225364Y88143D01*
G01X225173Y87050D02*
X225125Y86778D01*
G01X225220Y87324D02*
X225173Y87050D01*
G01X225269Y87597D02*
X225316Y87870D01*
G01X225269Y87597D02*
X225220Y87324D01*
G01X225077Y86505D02*
X225029Y86231D01*
G01X224885Y85412D02*
X224838Y85139D01*
G01X224981Y85958D02*
X224934Y85685D01*
G01X225029Y86231D02*
X224981Y85958D01*
G01X225125Y86778D02*
X225077Y86505D01*
G01X223819Y480354D02*
G02Y474055I0J-3149D01*
G02Y480354I0J3149D01*
G01Y474055D02*
G03Y480354I0J3149D01*
G03Y474055I0J-3149D01*
G01X251288Y73476D02*
X251350Y73537D01*
G01X251051Y73476D02*
X251398Y73810D01*
G01X250813Y73476D02*
X251445Y74082D01*
G01X250577Y73476D02*
X251494Y74356D01*
G01X250340Y73476D02*
X251543Y74630D01*
G01X250102Y73476D02*
X251590Y74903D01*
G01X249866Y73476D02*
X251638Y75176D01*
G01X249629Y73476D02*
X251687Y75449D01*
G01X249392Y73476D02*
X251735Y75723D01*
G01X249156Y73476D02*
X251783Y75996D01*
G01X248920Y73476D02*
X251830Y76269D01*
G01X248681Y73476D02*
X251879Y76543D01*
G01X248445Y73476D02*
X251927Y76817D01*
G01X248209Y73476D02*
X251974Y77089D01*
G01X247972Y73476D02*
X252023Y77362D01*
G01X247734Y73476D02*
X252072Y77636D01*
G01X247497Y73476D02*
X252119Y77910D01*
G01X247261Y73476D02*
X252167Y78183D01*
G01X247024Y73476D02*
X252216Y78456D01*
G01X246925Y73607D02*
X252264Y78730D01*
G01X246972Y73881D02*
X252312Y79003D01*
G01X247021Y74154D02*
X252359Y79276D01*
G01X247068Y74427D02*
X252408Y79549D01*
G01X247116Y74701D02*
X252456Y79823D01*
G01X247165Y74975D02*
X252503Y80096D01*
G01X247212Y75247D02*
X252552Y80369D01*
G01X247260Y75520D02*
X252601Y80643D01*
G01X247308Y75794D02*
X252648Y80916D01*
G01X247357Y76067D02*
X252696Y81190D01*
G01X247403Y76340D02*
X252745Y81463D01*
G01X252792Y81736D02*
X247452Y76613D01*
G01X243945Y73476D02*
X244078Y73602D01*
G01X252840Y82009D02*
X247501Y76886D01*
G01X252888Y82283D02*
X247548Y77160D01*
G01X243707Y73476D02*
X244125Y73876D01*
G01X252937Y82556D02*
X247596Y77433D01*
G01X243471Y73476D02*
X244173Y74149D01*
G01X243235Y73476D02*
X244221Y74422D01*
G01X252991Y82836D02*
X247645Y77706D01*
G01X242997Y73476D02*
X244267Y74695D01*
G01X253057Y83126D02*
X247692Y77980D01*
G01X253122Y83415D02*
X247740Y78253D01*
G01X253185Y83703D02*
X247789Y78526D01*
G01X253303Y84043D02*
X247836Y78799D01*
G01X253423Y84386D02*
X247883Y79072D01*
G01X253613Y84795D02*
X247932Y79346D01*
G01X253927Y85324D02*
X247980Y79619D01*
G01X259222Y90631D02*
X248027Y79891D01*
G01X259005Y90651D02*
X248076Y80165D01*
G01X258790Y90670D02*
X248124Y80439D01*
G01X258574Y90691D02*
X248171Y80711D01*
G01X258357Y90710D02*
X248220Y80985D01*
G01X251543Y74630D02*
X251494Y74356D01*
G01X251783Y75996D02*
X251830Y76269D01*
G01X251638Y75176D02*
X251590Y74903D01*
G01X251494Y74356D02*
X251445Y74082D01*
G01X251590Y74903D02*
X251543Y74630D01*
G01X252023Y77362D02*
X252072Y77636D01*
G01X251735Y75723D02*
X251687Y75449D01*
G01X251974Y77089D02*
X252023Y77362D01*
G01X252167Y78183D02*
X252216Y78456D01*
G01X252119Y77910D02*
X252167Y78183D01*
G01X252072Y77636D02*
X252119Y77910D01*
G01X251830Y76269D02*
X251879Y76543D01*
G01X251783Y75996D02*
X251735Y75723D01*
G01X251927Y76817D02*
X251974Y77089D01*
G01X251879Y76543D02*
X251927Y76817D01*
G01X252456Y79823D02*
X252503Y80096D01*
G01X251687Y75449D02*
X251638Y75176D01*
G01X252503Y80096D02*
X252552Y80369D01*
G01X252601Y80643D02*
X252648Y80916D01*
G01X252552Y80369D02*
X252601Y80643D01*
G01X252359Y79276D02*
X252408Y79549D01*
G01X252264Y78730D02*
X252312Y79003D01*
G01X252216Y78456D02*
X252264Y78730D01*
G01X252408Y79549D02*
X252456Y79823D01*
G01X252312Y79003D02*
X252359Y79276D01*
G01X252648Y80916D02*
X252696Y81190D01*
G01X247357Y76067D02*
X247308Y75794D01*
G01X247403Y76340D02*
X247357Y76067D01*
G01X247452Y76613D02*
X247403Y76340D01*
G01X247452Y76613D02*
X247501Y76886D01*
G01X247308Y75794D02*
X247260Y75520D01*
G01D02*
X247212Y75247D01*
G01X251051Y73476D02*
X251288D01*
G01X250577D02*
X250813D01*
G01D02*
X251051D01*
G01X250340D02*
X250577D01*
G01X250102D02*
X250340D01*
G01X247021Y74154D02*
X246972Y73881D01*
G01X247261Y73476D02*
X247497D01*
G01X249866D02*
X250102D01*
G01X246925Y73607D02*
X246901Y73476D01*
X247024D01*
G01X246972Y73881D02*
X246925Y73607D01*
G01X247212Y75247D02*
X247165Y74975D01*
G01D02*
X247116Y74701D01*
G01D02*
X247068Y74427D01*
G01D02*
X247021Y74154D01*
G01X247024Y73476D02*
X247261D01*
G01X249156D02*
X249392D01*
G01X249629D02*
X249866D01*
G01X248920D02*
X249156D01*
G01X249392D02*
X249629D01*
G01X248209D02*
X248445D01*
G01X247972D02*
X248209D01*
G01X247734D02*
X247972D01*
G01X248681D02*
X248920D01*
G01X248445D02*
X248681D01*
G01X247497D02*
X247734D01*
G01X247883Y79072D02*
X247836Y78799D01*
G01X247740Y78253D02*
X247692Y77980D01*
G01X247645Y77706D02*
X247596Y77433D01*
G01X247836Y78799D02*
X247789Y78526D01*
G01D02*
X247740Y78253D01*
G01X247692Y77980D02*
X247645Y77706D01*
G01X247596Y77433D02*
X247548Y77160D01*
G01D02*
X247501Y76886D01*
G01X247932Y79346D02*
X247883Y79072D01*
G01X248027Y79891D02*
X247980Y79619D01*
G01D02*
X247932Y79346D01*
G01X248124Y80439D02*
X248076Y80165D01*
G01X248220Y80985D02*
X248171Y80711D01*
G01D02*
X248124Y80439D01*
G01X248076Y80165D02*
X248027Y79891D01*
G01X251398Y73810D02*
X251350Y73537D01*
G01X251445Y74082D02*
X251398Y73810D01*
G01X251288Y73476D02*
X251339D01*
X251350Y73537D01*
G01X248267Y81258D02*
X248220Y80985D01*
G01X245130Y79612D02*
X245179Y79885D01*
G01X244939Y78519D02*
X244986Y78793D01*
G01X243471Y73476D02*
X243707D01*
G01D02*
X243945D01*
G01X242997D02*
X243235D01*
G01D02*
X243471D01*
G01X244748Y77427D02*
X244795Y77700D01*
G01X245035Y79066D02*
X245083Y79339D01*
G01D02*
X245130Y79612D01*
G01X244891Y78247D02*
X244939Y78519D01*
G01X244986Y78793D02*
X245035Y79066D01*
G01X245226Y80159D02*
X245274Y80432D01*
G01X245179Y79885D02*
X245226Y80159D01*
G01X244555Y76334D02*
X244604Y76607D01*
G01X244365Y75242D02*
X244411Y75514D01*
G01X244509Y76061D02*
X244555Y76334D01*
G01X244460Y75788D02*
X244509Y76061D01*
G01X244411Y75514D02*
X244460Y75788D01*
G01X244699Y77154D02*
X244748Y77427D01*
G01X244795Y77700D02*
X244843Y77974D01*
G01D02*
X244891Y78247D01*
G01X244651Y76880D02*
X244699Y77154D01*
G01X244604Y76607D02*
X244651Y76880D01*
G01X245323Y80705D02*
X245370Y80978D01*
G01D02*
X245418Y81251D01*
G01X245274Y80432D02*
X245323Y80705D01*
G01X244316Y74969D02*
X244365Y75242D01*
G01X243945Y73476D02*
X244055D01*
X244078Y73602D01*
G01D02*
X244125Y73876D01*
G01X244221Y74422D02*
X244267Y74695D01*
G01D02*
X244316Y74969D01*
G01X244125Y73876D02*
X244173Y74149D01*
G01D02*
X244221Y74422D01*
G01X251288Y73476D02*
X251350Y73537D01*
G01X251051Y73476D02*
X251398Y73810D01*
G01X250813Y73476D02*
X251445Y74082D01*
G01X250577Y73476D02*
X251494Y74356D01*
G01X250340Y73476D02*
X251543Y74630D01*
G01X250102Y73476D02*
X251590Y74903D01*
G01X249866Y73476D02*
X251638Y75176D01*
G01X249629Y73476D02*
X251687Y75449D01*
G01X249392Y73476D02*
X251735Y75723D01*
G01X249156Y73476D02*
X251783Y75996D01*
G01X248920Y73476D02*
X251830Y76269D01*
G01X248681Y73476D02*
X251879Y76543D01*
G01X248445Y73476D02*
X251927Y76817D01*
G01X248209Y73476D02*
X251974Y77089D01*
G01X247972Y73476D02*
X252023Y77362D01*
G01X247734Y73476D02*
X252072Y77636D01*
G01X247497Y73476D02*
X252119Y77910D01*
G01X247261Y73476D02*
X252167Y78183D01*
G01X247024Y73476D02*
X252216Y78456D01*
G01X246925Y73607D02*
X252264Y78730D01*
G01X246972Y73881D02*
X252312Y79003D01*
G01X247021Y74154D02*
X252359Y79276D01*
G01X247068Y74427D02*
X252408Y79549D01*
G01X247116Y74701D02*
X252456Y79823D01*
G01X247165Y74975D02*
X252503Y80096D01*
G01X247212Y75247D02*
X252552Y80369D01*
G01X247260Y75520D02*
X252601Y80643D01*
G01X247308Y75794D02*
X252648Y80916D01*
G01X247357Y76067D02*
X252696Y81190D01*
G01X247403Y76340D02*
X252745Y81463D01*
G01X252792Y81736D02*
X247452Y76613D01*
G01X243945Y73476D02*
X244078Y73602D01*
G01X252840Y82009D02*
X247501Y76886D01*
G01X252888Y82283D02*
X247548Y77160D01*
G01X243707Y73476D02*
X244125Y73876D01*
G01X252937Y82556D02*
X247596Y77433D01*
G01X243471Y73476D02*
X244173Y74149D01*
G01X243235Y73476D02*
X244221Y74422D01*
G01X252991Y82836D02*
X247645Y77706D01*
G01X242997Y73476D02*
X244267Y74695D01*
G01X253057Y83126D02*
X247692Y77980D01*
G01X253122Y83415D02*
X247740Y78253D01*
G01X253185Y83703D02*
X247789Y78526D01*
G01X253303Y84043D02*
X247836Y78799D01*
G01X253423Y84386D02*
X247883Y79072D01*
G01X253613Y84795D02*
X247932Y79346D01*
G01X253927Y85324D02*
X247980Y79619D01*
G01X259222Y90631D02*
X248027Y79891D01*
G01X259005Y90651D02*
X248076Y80165D01*
G01X258790Y90670D02*
X248124Y80439D01*
G01X258574Y90691D02*
X248171Y80711D01*
G01X258357Y90710D02*
X248220Y80985D01*
G01X251543Y74630D02*
X251494Y74356D01*
G01X251783Y75996D02*
X251830Y76269D01*
G01X251638Y75176D02*
X251590Y74903D01*
G01X251494Y74356D02*
X251445Y74082D01*
G01X251590Y74903D02*
X251543Y74630D01*
G01X252023Y77362D02*
X252072Y77636D01*
G01X251735Y75723D02*
X251687Y75449D01*
G01X251974Y77089D02*
X252023Y77362D01*
G01X252167Y78183D02*
X252216Y78456D01*
G01X252119Y77910D02*
X252167Y78183D01*
G01X252072Y77636D02*
X252119Y77910D01*
G01X251830Y76269D02*
X251879Y76543D01*
G01X251783Y75996D02*
X251735Y75723D01*
G01X251927Y76817D02*
X251974Y77089D01*
G01X251879Y76543D02*
X251927Y76817D01*
G01X252456Y79823D02*
X252503Y80096D01*
G01X251687Y75449D02*
X251638Y75176D01*
G01X252503Y80096D02*
X252552Y80369D01*
G01X252601Y80643D02*
X252648Y80916D01*
G01X252552Y80369D02*
X252601Y80643D01*
G01X252359Y79276D02*
X252408Y79549D01*
G01X252264Y78730D02*
X252312Y79003D01*
G01X252216Y78456D02*
X252264Y78730D01*
G01X252408Y79549D02*
X252456Y79823D01*
G01X252312Y79003D02*
X252359Y79276D01*
G01X252648Y80916D02*
X252696Y81190D01*
G01X247357Y76067D02*
X247308Y75794D01*
G01X247403Y76340D02*
X247357Y76067D01*
G01X247452Y76613D02*
X247403Y76340D01*
G01X247452Y76613D02*
X247501Y76886D01*
G01X247308Y75794D02*
X247260Y75520D01*
G01D02*
X247212Y75247D01*
G01X251051Y73476D02*
X251288D01*
G01X250577D02*
X250813D01*
G01D02*
X251051D01*
G01X250340D02*
X250577D01*
G01X250102D02*
X250340D01*
G01X247021Y74154D02*
X246972Y73881D01*
G01X247261Y73476D02*
X247497D01*
G01X249866D02*
X250102D01*
G01X246925Y73607D02*
X246901Y73476D01*
X247024D01*
G01X246972Y73881D02*
X246925Y73607D01*
G01X247212Y75247D02*
X247165Y74975D01*
G01D02*
X247116Y74701D01*
G01D02*
X247068Y74427D01*
G01D02*
X247021Y74154D01*
G01X247024Y73476D02*
X247261D01*
G01X249156D02*
X249392D01*
G01X249629D02*
X249866D01*
G01X248920D02*
X249156D01*
G01X249392D02*
X249629D01*
G01X248209D02*
X248445D01*
G01X247972D02*
X248209D01*
G01X247734D02*
X247972D01*
G01X248681D02*
X248920D01*
G01X248445D02*
X248681D01*
G01X247497D02*
X247734D01*
G01X247883Y79072D02*
X247836Y78799D01*
G01X247740Y78253D02*
X247692Y77980D01*
G01X247645Y77706D02*
X247596Y77433D01*
G01X247836Y78799D02*
X247789Y78526D01*
G01D02*
X247740Y78253D01*
G01X247692Y77980D02*
X247645Y77706D01*
G01X247596Y77433D02*
X247548Y77160D01*
G01D02*
X247501Y76886D01*
G01X247932Y79346D02*
X247883Y79072D01*
G01X248027Y79891D02*
X247980Y79619D01*
G01D02*
X247932Y79346D01*
G01X248124Y80439D02*
X248076Y80165D01*
G01X248220Y80985D02*
X248171Y80711D01*
G01D02*
X248124Y80439D01*
G01X248076Y80165D02*
X248027Y79891D01*
G01X251398Y73810D02*
X251350Y73537D01*
G01X251445Y74082D02*
X251398Y73810D01*
G01X251288Y73476D02*
X251339D01*
X251350Y73537D01*
G01X248267Y81258D02*
X248220Y80985D01*
G01X245130Y79612D02*
X245179Y79885D01*
G01X244939Y78519D02*
X244986Y78793D01*
G01X243471Y73476D02*
X243707D01*
G01D02*
X243945D01*
G01X242997D02*
X243235D01*
G01D02*
X243471D01*
G01X244748Y77427D02*
X244795Y77700D01*
G01X245035Y79066D02*
X245083Y79339D01*
G01D02*
X245130Y79612D01*
G01X244891Y78247D02*
X244939Y78519D01*
G01X244986Y78793D02*
X245035Y79066D01*
G01X245226Y80159D02*
X245274Y80432D01*
G01X245179Y79885D02*
X245226Y80159D01*
G01X244555Y76334D02*
X244604Y76607D01*
G01X244365Y75242D02*
X244411Y75514D01*
G01X244509Y76061D02*
X244555Y76334D01*
G01X244460Y75788D02*
X244509Y76061D01*
G01X244411Y75514D02*
X244460Y75788D01*
G01X244699Y77154D02*
X244748Y77427D01*
G01X244795Y77700D02*
X244843Y77974D01*
G01D02*
X244891Y78247D01*
G01X244651Y76880D02*
X244699Y77154D01*
G01X244604Y76607D02*
X244651Y76880D01*
G01X245323Y80705D02*
X245370Y80978D01*
G01D02*
X245418Y81251D01*
G01X245274Y80432D02*
X245323Y80705D01*
G01X244316Y74969D02*
X244365Y75242D01*
G01X243945Y73476D02*
X244055D01*
X244078Y73602D01*
G01D02*
X244125Y73876D01*
G01X244221Y74422D02*
X244267Y74695D01*
G01D02*
X244316Y74969D01*
G01X244125Y73876D02*
X244173Y74149D01*
G01D02*
X244221Y74422D01*
G01X259654Y90591D02*
X255198Y86316D01*
G01X259438Y90611D02*
X254736Y86100D01*
G01X258103Y90693D02*
X248267Y81258D01*
G01X257842Y90670D02*
X248315Y81531D01*
G01X257579Y90645D02*
X248364Y81804D01*
G01X257318Y90621D02*
X248411Y82077D01*
G01X257055Y90597D02*
X248459Y82351D01*
G01X256724Y90507D02*
X248507Y82624D01*
G01X256392Y90415D02*
X248555Y82897D01*
G01X256059Y90322D02*
X248602Y83170D01*
G01X255658Y90165D02*
X248651Y83444D01*
G01X255187Y89942D02*
X248699Y83717D01*
G01X254538Y89545D02*
X248746Y83990D01*
G01X254131Y89382D02*
X248795Y84263D01*
G01X254180Y89656D02*
X248844Y84537D01*
G01X254227Y89929D02*
X248890Y84810D01*
G01X254275Y90202D02*
X248939Y85083D01*
G01X254204Y90361D02*
X248988Y85356D01*
G01X253967Y90361D02*
X249034Y85629D01*
G01X253729Y90361D02*
X249082Y85903D01*
G01X253493Y90361D02*
X249131Y86176D01*
G01X253257Y90361D02*
X249179Y86449D01*
G01X253020Y90361D02*
X249226Y86722D01*
G01X252783Y90361D02*
X249275Y86996D01*
G01X252547Y90361D02*
X249323Y87269D01*
G01X252309Y90361D02*
X249370Y87542D01*
G01X252072Y90361D02*
X249419Y87815D01*
G01X251836Y90361D02*
X249466Y88088D01*
G01X251598Y90361D02*
X249514Y88362D01*
G01X251361Y90361D02*
X249563Y88634D01*
G01X251125Y90361D02*
X249610Y88908D01*
G01X250888Y90361D02*
X249658Y89182D01*
G01X250650Y90361D02*
X249706Y89454D01*
G01X250414Y90361D02*
X249754Y89728D01*
G01X250177Y90361D02*
X249801Y90001D01*
G01X249940Y90361D02*
X249850Y90274D01*
G01X252745Y81463D02*
X252696Y81190D01*
G01X254275Y90202D02*
X254303Y90361D01*
X254204D01*
G01X254227Y89929D02*
X254275Y90202D01*
G01X254131Y89382D02*
X254180Y89656D01*
G01D02*
X254227Y89929D01*
G01X253729Y90361D02*
X253493D01*
G01D02*
X253257D01*
G01X254204D02*
X253967D01*
G01D02*
X253729D01*
G01X253257D02*
X253020D01*
G01X252792Y81736D02*
X252745Y81463D01*
G01X252840Y82009D02*
X252792Y81736D01*
G01X251598Y90361D02*
X251361D01*
G01X250414D02*
X250177D01*
G01X250888D02*
X250650D01*
G01X253020D02*
X252783D01*
G01X251125D02*
X250888D01*
G01X251361D02*
X251125D01*
G01X250650D02*
X250414D01*
G01X252309D02*
X252072D01*
G01X252547D02*
X252309D01*
G01X251836D02*
X251598D01*
G01X252783D02*
X252547D01*
G01X250177D02*
X249940D01*
G01X252072D02*
X251836D01*
G01X252888Y82283D02*
X252840Y82009D01*
G01X248795Y84263D02*
X248746Y83990D01*
G01X252937Y82556D02*
X252888Y82283D01*
G01X248746Y83990D02*
X248699Y83717D01*
G01X249275Y86996D02*
X249323Y87269D01*
G01D02*
X249370Y87542D01*
G01X249419Y87815D02*
X249466Y88088D01*
G01X249179Y86449D02*
X249131Y86176D01*
G01D02*
X249082Y85903D01*
G01X249226Y86722D02*
X249275Y86996D01*
G01X249179Y86449D02*
X249226Y86722D01*
G01X249466Y88088D02*
X249514Y88362D01*
G01X249370Y87542D02*
X249419Y87815D01*
G01X249940Y90361D02*
X249865D01*
X249850Y90274D01*
G01X249801Y90001D02*
X249850Y90274D01*
G01X249563Y88634D02*
X249610Y88908D01*
G01X249514Y88362D02*
X249563Y88634D01*
G01X249754Y89728D02*
X249801Y90001D01*
G01X249610Y88908D02*
X249658Y89182D01*
G01D02*
X249706Y89454D01*
G01D02*
X249754Y89728D01*
G01X249082Y85903D02*
X249034Y85629D01*
G01X248459Y82351D02*
X248411Y82077D01*
G01X248507Y82624D02*
X248459Y82351D01*
G01X248411Y82077D02*
X248364Y81804D01*
G01X249034Y85629D02*
X248988Y85356D01*
G01X248364Y81804D02*
X248315Y81531D01*
G01D02*
X248267Y81258D01*
G01X248844Y84537D02*
X248795Y84263D01*
G01X248890Y84810D02*
X248844Y84537D01*
G01X248939Y85083D02*
X248890Y84810D01*
G01X248988Y85356D02*
X248939Y85083D01*
G01X248699Y83717D02*
X248651Y83444D01*
G01X248602Y83170D02*
X248555Y82897D01*
G01X248651Y83444D02*
X248602Y83170D01*
G01X248555Y82897D02*
X248507Y82624D01*
G01X245802Y83437D02*
X245754Y83163D01*
G01X245945Y84256D02*
X245898Y83983D01*
G01X245993Y84529D02*
X245945Y84256D01*
G01X245849Y83710D02*
X245802Y83437D01*
G01X245898Y83983D02*
X245849Y83710D01*
G01X245610Y82344D02*
X245658Y82618D01*
G01X245561Y82070D02*
X245610Y82344D01*
G01X245658Y82618D02*
X245705Y82890D01*
G01X245754Y83163D02*
X245705Y82890D01*
G01X245466Y81524D02*
X245514Y81798D01*
G01X245418Y81251D02*
X245466Y81524D01*
G01X245514Y81798D02*
X245561Y82070D01*
G01X259654Y90591D02*
X255198Y86316D01*
G01X259438Y90611D02*
X254736Y86100D01*
G01X258103Y90693D02*
X248267Y81258D01*
G01X257842Y90670D02*
X248315Y81531D01*
G01X257579Y90645D02*
X248364Y81804D01*
G01X257318Y90621D02*
X248411Y82077D01*
G01X257055Y90597D02*
X248459Y82351D01*
G01X256724Y90507D02*
X248507Y82624D01*
G01X256392Y90415D02*
X248555Y82897D01*
G01X256059Y90322D02*
X248602Y83170D01*
G01X255658Y90165D02*
X248651Y83444D01*
G01X255187Y89942D02*
X248699Y83717D01*
G01X254538Y89545D02*
X248746Y83990D01*
G01X254131Y89382D02*
X248795Y84263D01*
G01X254180Y89656D02*
X248844Y84537D01*
G01X254227Y89929D02*
X248890Y84810D01*
G01X254275Y90202D02*
X248939Y85083D01*
G01X254204Y90361D02*
X248988Y85356D01*
G01X253967Y90361D02*
X249034Y85629D01*
G01X253729Y90361D02*
X249082Y85903D01*
G01X253493Y90361D02*
X249131Y86176D01*
G01X253257Y90361D02*
X249179Y86449D01*
G01X253020Y90361D02*
X249226Y86722D01*
G01X252783Y90361D02*
X249275Y86996D01*
G01X252547Y90361D02*
X249323Y87269D01*
G01X252309Y90361D02*
X249370Y87542D01*
G01X252072Y90361D02*
X249419Y87815D01*
G01X251836Y90361D02*
X249466Y88088D01*
G01X251598Y90361D02*
X249514Y88362D01*
G01X251361Y90361D02*
X249563Y88634D01*
G01X251125Y90361D02*
X249610Y88908D01*
G01X250888Y90361D02*
X249658Y89182D01*
G01X250650Y90361D02*
X249706Y89454D01*
G01X250414Y90361D02*
X249754Y89728D01*
G01X250177Y90361D02*
X249801Y90001D01*
G01X249940Y90361D02*
X249850Y90274D01*
G01X252745Y81463D02*
X252696Y81190D01*
G01X254275Y90202D02*
X254303Y90361D01*
X254204D01*
G01X254227Y89929D02*
X254275Y90202D01*
G01X254131Y89382D02*
X254180Y89656D01*
G01D02*
X254227Y89929D01*
G01X253729Y90361D02*
X253493D01*
G01D02*
X253257D01*
G01X254204D02*
X253967D01*
G01D02*
X253729D01*
G01X253257D02*
X253020D01*
G01X252792Y81736D02*
X252745Y81463D01*
G01X252840Y82009D02*
X252792Y81736D01*
G01X251598Y90361D02*
X251361D01*
G01X250414D02*
X250177D01*
G01X250888D02*
X250650D01*
G01X253020D02*
X252783D01*
G01X251125D02*
X250888D01*
G01X251361D02*
X251125D01*
G01X250650D02*
X250414D01*
G01X252309D02*
X252072D01*
G01X252547D02*
X252309D01*
G01X251836D02*
X251598D01*
G01X252783D02*
X252547D01*
G01X250177D02*
X249940D01*
G01X252072D02*
X251836D01*
G01X252888Y82283D02*
X252840Y82009D01*
G01X248795Y84263D02*
X248746Y83990D01*
G01X252937Y82556D02*
X252888Y82283D01*
G01X248746Y83990D02*
X248699Y83717D01*
G01X249275Y86996D02*
X249323Y87269D01*
G01D02*
X249370Y87542D01*
G01X249419Y87815D02*
X249466Y88088D01*
G01X249179Y86449D02*
X249131Y86176D01*
G01D02*
X249082Y85903D01*
G01X249226Y86722D02*
X249275Y86996D01*
G01X249179Y86449D02*
X249226Y86722D01*
G01X249466Y88088D02*
X249514Y88362D01*
G01X249370Y87542D02*
X249419Y87815D01*
G01X249940Y90361D02*
X249865D01*
X249850Y90274D01*
G01X249801Y90001D02*
X249850Y90274D01*
G01X249563Y88634D02*
X249610Y88908D01*
G01X249514Y88362D02*
X249563Y88634D01*
G01X249754Y89728D02*
X249801Y90001D01*
G01X249610Y88908D02*
X249658Y89182D01*
G01D02*
X249706Y89454D01*
G01D02*
X249754Y89728D01*
G01X249082Y85903D02*
X249034Y85629D01*
G01X248459Y82351D02*
X248411Y82077D01*
G01X248507Y82624D02*
X248459Y82351D01*
G01X248411Y82077D02*
X248364Y81804D01*
G01X249034Y85629D02*
X248988Y85356D01*
G01X248364Y81804D02*
X248315Y81531D01*
G01D02*
X248267Y81258D01*
G01X248844Y84537D02*
X248795Y84263D01*
G01X248890Y84810D02*
X248844Y84537D01*
G01X248939Y85083D02*
X248890Y84810D01*
G01X248988Y85356D02*
X248939Y85083D01*
G01X248699Y83717D02*
X248651Y83444D01*
G01X248602Y83170D02*
X248555Y82897D01*
G01X248651Y83444D02*
X248602Y83170D01*
G01X248555Y82897D02*
X248507Y82624D01*
G01X245802Y83437D02*
X245754Y83163D01*
G01X245945Y84256D02*
X245898Y83983D01*
G01X245993Y84529D02*
X245945Y84256D01*
G01X245849Y83710D02*
X245802Y83437D01*
G01X245898Y83983D02*
X245849Y83710D01*
G01X245610Y82344D02*
X245658Y82618D01*
G01X245561Y82070D02*
X245610Y82344D01*
G01X245658Y82618D02*
X245705Y82890D01*
G01X245754Y83163D02*
X245705Y82890D01*
G01X245466Y81524D02*
X245514Y81798D01*
G01X245418Y81251D02*
X245466Y81524D01*
G01X245514Y81798D02*
X245561Y82070D01*
G01X272154Y73271D02*
X275027Y76026D01*
G01X271846Y73203D02*
X275131Y76354D01*
G01X271588Y73182D02*
X275234Y76680D01*
G01X271330Y73163D02*
X275338Y77007D01*
G01X271073Y73144D02*
X275442Y77334D01*
G01X270815Y73122D02*
X275546Y77662D01*
G01X270601Y73144D02*
X275650Y77988D01*
G01X270386Y73165D02*
X275754Y78315D01*
G01X270171Y73187D02*
X275858Y78642D01*
G01X269957Y73209D02*
X275005Y78051D01*
G01X269763Y73249D02*
X274413Y77710D01*
G01X269588Y73309D02*
X274000Y77541D01*
G01X269413Y73367D02*
X273646Y77429D01*
G01X269236Y73427D02*
X273376Y77397D01*
G01X269063Y73485D02*
X273110Y77369D01*
G01X268914Y73569D02*
X272886Y77381D01*
G01X268772Y73662D02*
X272676Y77407D01*
G01X268630Y73754D02*
X272482Y77449D01*
G01X268490Y73846D02*
X272318Y77518D01*
G01X268349Y73938D02*
X272166Y77600D01*
G01X268234Y74056D02*
X272049Y77714D01*
G01X268124Y74178D02*
X271949Y77846D01*
G01X268014Y74299D02*
X271872Y77999D01*
G01X267904Y74421D02*
X271821Y78178D01*
G01X267795Y74543D02*
X271784Y78369D01*
G01X267712Y74691D02*
X271777Y78589D01*
G01X267633Y74842D02*
X271775Y78816D01*
G01X267553Y74992D02*
X271804Y79069D01*
G01X267473Y75143D02*
X271836Y79328D01*
G01X267393Y75294D02*
X271880Y79598D01*
G01X267344Y75474D02*
X271929Y79871D01*
G01X267295Y75654D02*
X271976Y80144D01*
G01X267247Y75835D02*
X272025Y80418D01*
G01X267198Y76016D02*
X272072Y80692D01*
G01X267156Y76202D02*
X272120Y80964D01*
G01X267142Y76415D02*
X272169Y81237D01*
G01X267127Y76628D02*
X272216Y81511D01*
G01X267112Y76842D02*
X272265Y81785D01*
G01X267097Y77055D02*
X272312Y82057D01*
G01X267107Y77291D02*
X272360Y82330D01*
G01X267131Y77542D02*
X272409Y82604D01*
G01X267157Y77794D02*
X272456Y82877D01*
G01X267181Y78044D02*
X272505Y83151D01*
G01X267215Y78303D02*
X272553Y83423D01*
G01X267263Y78576D02*
X272600Y83697D01*
G01X267310Y78850D02*
X272649Y83971D01*
G01X272696Y84244D02*
X267359Y79123D01*
G01X261471Y73476D02*
X261547Y73548D01*
G01X267407Y79396D02*
X272745Y84516D01*
G01X261235Y73476D02*
X261596Y73822D01*
G01X267454Y79669D02*
X272793Y84790D01*
G01X260999Y73476D02*
X261644Y74095D01*
G01X260761Y73476D02*
X261691Y74368D01*
G01X267503Y79943D02*
X272841Y85064D01*
G01X260525Y73476D02*
X261740Y74641D01*
G01X267550Y80216D02*
X272889Y85336D01*
G01X267598Y80488D02*
X272936Y85610D01*
G01X260289Y73476D02*
X261787Y74914D01*
G01X260051Y73476D02*
X261835Y75188D01*
G01X267645Y80762D02*
X272985Y85883D01*
G01X267694Y81035D02*
X273033Y86157D01*
G01X259814Y73476D02*
X261884Y75462D01*
G01X259578Y73476D02*
X261931Y75734D01*
G01X259340Y73476D02*
X261979Y76007D01*
G01X259103Y73476D02*
X262027Y76281D01*
G01X258867Y73476D02*
X262075Y76554D01*
G01X258630Y73476D02*
X262122Y76827D01*
G01X258392Y73476D02*
X262171Y77100D01*
G01X258156Y73476D02*
X262219Y77373D01*
G01X257919Y73476D02*
X262266Y77647D01*
G01X257682Y73476D02*
X262315Y77919D01*
G01X257446Y73476D02*
X262362Y78193D01*
G01X257208Y73476D02*
X262410Y78466D01*
G01X257117Y73616D02*
X262459Y78740D01*
G01X257166Y73889D02*
X262506Y79012D01*
G01X257214Y74162D02*
X262554Y79285D01*
G01X257261Y74436D02*
X262602Y79558D01*
G01X257310Y74709D02*
X262650Y79832D01*
G01X257358Y74982D02*
X262697Y80105D01*
G01X257405Y75255D02*
X262746Y80378D01*
G01X257454Y75529D02*
X262794Y80652D01*
G01X257503Y75803D02*
X262841Y80925D01*
G01X257550Y76075D02*
X262890Y81198D01*
G01X257598Y76349D02*
X262937Y81471D01*
G01X257646Y76622D02*
X262985Y81744D01*
G01X257694Y76896D02*
X263034Y82018D01*
G01X257741Y77169D02*
X263081Y82291D01*
G01X257790Y77442D02*
X263129Y82563D01*
G01X257839Y77715D02*
X263178Y82837D01*
G01X257886Y77988D02*
X263218Y83104D01*
G01X257934Y78262D02*
X263249Y83361D01*
G01X257983Y78535D02*
X263281Y83617D01*
G01X258030Y78808D02*
X263312Y83875D01*
G01X258078Y79082D02*
X263343Y84133D01*
G01X258127Y79355D02*
X263376Y84390D01*
G01X258174Y79628D02*
X263405Y84647D01*
G01X258221Y79902D02*
X263411Y84879D01*
G01X263408Y85104D02*
X258270Y80175D01*
G01X258319Y80448D02*
X263407Y85330D01*
G01X258367Y80721D02*
X263405Y85555D01*
G01X258414Y80995D02*
X263403Y85781D01*
G01X267310Y78850D02*
X267263Y78576D01*
G01X267742Y81308D02*
X267694Y81035D01*
G01D02*
X267645Y80762D01*
G01D02*
X267598Y80488D01*
G01X267550Y80216D02*
X267503Y79943D01*
G01D02*
X267454Y79669D01*
G01X267598Y80488D02*
X267550Y80216D01*
G01X267454Y79669D02*
X267407Y79396D01*
G01X267310Y78850D02*
X267359Y79123D01*
G01X271976Y80144D02*
X271929Y79871D01*
G01D02*
X271880Y79598D01*
G01X267407Y79396D02*
X267359Y79123D01*
G01X272025Y80418D02*
X272072Y80692D01*
G01D02*
X272120Y80964D01*
G01X267263Y78576D02*
X267215Y78303D01*
G01X272025Y80418D02*
X271976Y80144D01*
G01X272120Y80964D02*
X272169Y81237D01*
G01X258867Y73476D02*
X259103D01*
G01X259578D02*
X259814D01*
G01X259340D02*
X259578D01*
G01X259103D02*
X259340D01*
G01X259814D02*
X260051D01*
G01D02*
X260289D01*
G01D02*
X260525D01*
G01X257166Y73889D02*
X257117Y73616D01*
G01X257214Y74162D02*
X257166Y73889D01*
G01X257208Y73476D02*
X257446D01*
G01D02*
X257682D01*
G01X257261Y74436D02*
X257214Y74162D01*
G01X257117Y73616D02*
X257093Y73476D01*
X257208D01*
G01X257358Y74982D02*
X257310Y74709D01*
G01D02*
X257261Y74436D01*
G01X258630Y73476D02*
X258867D01*
G01X257682D02*
X257919D01*
G01X258392D02*
X258630D01*
G01X257919D02*
X258156D01*
G01D02*
X258392D01*
G01X257405Y75255D02*
X257358Y74982D01*
G01X257741Y77169D02*
X257694Y76896D01*
G01X258174Y79628D02*
X258127Y79355D01*
G01D02*
X258078Y79082D01*
G01X257983Y78535D02*
X257934Y78262D01*
G01X258030Y78808D02*
X257983Y78535D01*
G01X258078Y79082D02*
X258030Y78808D01*
G01X257646Y76622D02*
X257598Y76349D01*
G01D02*
X257550Y76075D01*
G01X257934Y78262D02*
X257886Y77988D01*
G01X257550Y76075D02*
X257503Y75803D01*
G01D02*
X257454Y75529D01*
G01X257886Y77988D02*
X257839Y77715D01*
G01D02*
X257790Y77442D01*
G01X257454Y75529D02*
X257405Y75255D01*
G01X257694Y76896D02*
X257646Y76622D01*
G01X257790Y77442D02*
X257741Y77169D01*
G01X258221Y79902D02*
X258174Y79628D01*
G01X258463Y81268D02*
X258414Y80995D01*
G01X258319Y80448D02*
X258270Y80175D01*
G01X258414Y80995D02*
X258367Y80721D01*
G01X261740Y74641D02*
X261691Y74368D01*
G01X261644Y74095D02*
X261596Y73822D01*
G01X262266Y77647D02*
X262219Y77373D01*
G01X261691Y74368D02*
X261644Y74095D01*
G01X262315Y77919D02*
X262266Y77647D01*
G01X262410Y78466D02*
X262362Y78193D01*
G01X261596Y73822D02*
X261547Y73548D01*
G01X262459Y78740D02*
X262410Y78466D01*
G01X262362Y78193D02*
X262315Y77919D01*
G01X261471Y73476D02*
X261535D01*
X261547Y73548D01*
G01X261979Y76007D02*
X261931Y75734D01*
G01X262075Y76554D02*
X262027Y76281D01*
G01D02*
X261979Y76007D01*
G01X262122Y76827D02*
X262075Y76554D01*
G01X262171Y77100D02*
X262122Y76827D01*
G01X261835Y75188D02*
X261787Y74914D01*
G01X262219Y77373D02*
X262171Y77100D01*
G01X261787Y74914D02*
X261740Y74641D01*
G01X261884Y75462D02*
X261835Y75188D01*
G01X261931Y75734D02*
X261884Y75462D01*
G01X262794Y80652D02*
X262746Y80378D01*
G01X262890Y81198D02*
X262841Y80925D01*
G01X262506Y79012D02*
X262459Y78740D01*
G01X260761Y73476D02*
X260999D01*
G01X260525D02*
X260761D01*
G01X260999D02*
X261235D01*
G01X262650Y79832D02*
X262602Y79558D01*
G01X262697Y80105D02*
X262650Y79832D01*
G01X262602Y79558D02*
X262554Y79285D01*
G01D02*
X262506Y79012D01*
G01X261235Y73476D02*
X261471D01*
G01X262841Y80925D02*
X262794Y80652D01*
G01X262746Y80378D02*
X262697Y80105D01*
G01X258221Y79902D02*
X258270Y80175D01*
G01X258367Y80721D02*
X258319Y80448D01*
G01X272154Y73271D02*
X275027Y76026D01*
G01X271846Y73203D02*
X275131Y76354D01*
G01X271588Y73182D02*
X275234Y76680D01*
G01X271330Y73163D02*
X275338Y77007D01*
G01X271073Y73144D02*
X275442Y77334D01*
G01X270815Y73122D02*
X275546Y77662D01*
G01X270601Y73144D02*
X275650Y77988D01*
G01X270386Y73165D02*
X275754Y78315D01*
G01X270171Y73187D02*
X275858Y78642D01*
G01X269957Y73209D02*
X275005Y78051D01*
G01X269763Y73249D02*
X274413Y77710D01*
G01X269588Y73309D02*
X274000Y77541D01*
G01X269413Y73367D02*
X273646Y77429D01*
G01X269236Y73427D02*
X273376Y77397D01*
G01X269063Y73485D02*
X273110Y77369D01*
G01X268914Y73569D02*
X272886Y77381D01*
G01X268772Y73662D02*
X272676Y77407D01*
G01X268630Y73754D02*
X272482Y77449D01*
G01X268490Y73846D02*
X272318Y77518D01*
G01X268349Y73938D02*
X272166Y77600D01*
G01X268234Y74056D02*
X272049Y77714D01*
G01X268124Y74178D02*
X271949Y77846D01*
G01X268014Y74299D02*
X271872Y77999D01*
G01X267904Y74421D02*
X271821Y78178D01*
G01X267795Y74543D02*
X271784Y78369D01*
G01X267712Y74691D02*
X271777Y78589D01*
G01X267633Y74842D02*
X271775Y78816D01*
G01X267553Y74992D02*
X271804Y79069D01*
G01X267473Y75143D02*
X271836Y79328D01*
G01X267393Y75294D02*
X271880Y79598D01*
G01X267344Y75474D02*
X271929Y79871D01*
G01X267295Y75654D02*
X271976Y80144D01*
G01X267247Y75835D02*
X272025Y80418D01*
G01X267198Y76016D02*
X272072Y80692D01*
G01X267156Y76202D02*
X272120Y80964D01*
G01X267142Y76415D02*
X272169Y81237D01*
G01X267127Y76628D02*
X272216Y81511D01*
G01X267112Y76842D02*
X272265Y81785D01*
G01X267097Y77055D02*
X272312Y82057D01*
G01X267107Y77291D02*
X272360Y82330D01*
G01X267131Y77542D02*
X272409Y82604D01*
G01X267157Y77794D02*
X272456Y82877D01*
G01X267181Y78044D02*
X272505Y83151D01*
G01X267215Y78303D02*
X272553Y83423D01*
G01X267263Y78576D02*
X272600Y83697D01*
G01X267310Y78850D02*
X272649Y83971D01*
G01X272696Y84244D02*
X267359Y79123D01*
G01X261471Y73476D02*
X261547Y73548D01*
G01X267407Y79396D02*
X272745Y84516D01*
G01X261235Y73476D02*
X261596Y73822D01*
G01X267454Y79669D02*
X272793Y84790D01*
G01X260999Y73476D02*
X261644Y74095D01*
G01X260761Y73476D02*
X261691Y74368D01*
G01X267503Y79943D02*
X272841Y85064D01*
G01X260525Y73476D02*
X261740Y74641D01*
G01X267550Y80216D02*
X272889Y85336D01*
G01X267598Y80488D02*
X272936Y85610D01*
G01X260289Y73476D02*
X261787Y74914D01*
G01X260051Y73476D02*
X261835Y75188D01*
G01X267645Y80762D02*
X272985Y85883D01*
G01X267694Y81035D02*
X273033Y86157D01*
G01X259814Y73476D02*
X261884Y75462D01*
G01X259578Y73476D02*
X261931Y75734D01*
G01X259340Y73476D02*
X261979Y76007D01*
G01X259103Y73476D02*
X262027Y76281D01*
G01X258867Y73476D02*
X262075Y76554D01*
G01X258630Y73476D02*
X262122Y76827D01*
G01X258392Y73476D02*
X262171Y77100D01*
G01X258156Y73476D02*
X262219Y77373D01*
G01X257919Y73476D02*
X262266Y77647D01*
G01X257682Y73476D02*
X262315Y77919D01*
G01X257446Y73476D02*
X262362Y78193D01*
G01X257208Y73476D02*
X262410Y78466D01*
G01X257117Y73616D02*
X262459Y78740D01*
G01X257166Y73889D02*
X262506Y79012D01*
G01X257214Y74162D02*
X262554Y79285D01*
G01X257261Y74436D02*
X262602Y79558D01*
G01X257310Y74709D02*
X262650Y79832D01*
G01X257358Y74982D02*
X262697Y80105D01*
G01X257405Y75255D02*
X262746Y80378D01*
G01X257454Y75529D02*
X262794Y80652D01*
G01X257503Y75803D02*
X262841Y80925D01*
G01X257550Y76075D02*
X262890Y81198D01*
G01X257598Y76349D02*
X262937Y81471D01*
G01X257646Y76622D02*
X262985Y81744D01*
G01X257694Y76896D02*
X263034Y82018D01*
G01X257741Y77169D02*
X263081Y82291D01*
G01X257790Y77442D02*
X263129Y82563D01*
G01X257839Y77715D02*
X263178Y82837D01*
G01X257886Y77988D02*
X263218Y83104D01*
G01X257934Y78262D02*
X263249Y83361D01*
G01X257983Y78535D02*
X263281Y83617D01*
G01X258030Y78808D02*
X263312Y83875D01*
G01X258078Y79082D02*
X263343Y84133D01*
G01X258127Y79355D02*
X263376Y84390D01*
G01X258174Y79628D02*
X263405Y84647D01*
G01X258221Y79902D02*
X263411Y84879D01*
G01X263408Y85104D02*
X258270Y80175D01*
G01X258319Y80448D02*
X263407Y85330D01*
G01X258367Y80721D02*
X263405Y85555D01*
G01X258414Y80995D02*
X263403Y85781D01*
G01X267310Y78850D02*
X267263Y78576D01*
G01X267742Y81308D02*
X267694Y81035D01*
G01D02*
X267645Y80762D01*
G01D02*
X267598Y80488D01*
G01X267550Y80216D02*
X267503Y79943D01*
G01D02*
X267454Y79669D01*
G01X267598Y80488D02*
X267550Y80216D01*
G01X267454Y79669D02*
X267407Y79396D01*
G01X267310Y78850D02*
X267359Y79123D01*
G01X271976Y80144D02*
X271929Y79871D01*
G01D02*
X271880Y79598D01*
G01X267407Y79396D02*
X267359Y79123D01*
G01X272025Y80418D02*
X272072Y80692D01*
G01D02*
X272120Y80964D01*
G01X267263Y78576D02*
X267215Y78303D01*
G01X272025Y80418D02*
X271976Y80144D01*
G01X272120Y80964D02*
X272169Y81237D01*
G01X258867Y73476D02*
X259103D01*
G01X259578D02*
X259814D01*
G01X259340D02*
X259578D01*
G01X259103D02*
X259340D01*
G01X259814D02*
X260051D01*
G01D02*
X260289D01*
G01D02*
X260525D01*
G01X257166Y73889D02*
X257117Y73616D01*
G01X257214Y74162D02*
X257166Y73889D01*
G01X257208Y73476D02*
X257446D01*
G01D02*
X257682D01*
G01X257261Y74436D02*
X257214Y74162D01*
G01X257117Y73616D02*
X257093Y73476D01*
X257208D01*
G01X257358Y74982D02*
X257310Y74709D01*
G01D02*
X257261Y74436D01*
G01X258630Y73476D02*
X258867D01*
G01X257682D02*
X257919D01*
G01X258392D02*
X258630D01*
G01X257919D02*
X258156D01*
G01D02*
X258392D01*
G01X257405Y75255D02*
X257358Y74982D01*
G01X257741Y77169D02*
X257694Y76896D01*
G01X258174Y79628D02*
X258127Y79355D01*
G01D02*
X258078Y79082D01*
G01X257983Y78535D02*
X257934Y78262D01*
G01X258030Y78808D02*
X257983Y78535D01*
G01X258078Y79082D02*
X258030Y78808D01*
G01X257646Y76622D02*
X257598Y76349D01*
G01D02*
X257550Y76075D01*
G01X257934Y78262D02*
X257886Y77988D01*
G01X257550Y76075D02*
X257503Y75803D01*
G01D02*
X257454Y75529D01*
G01X257886Y77988D02*
X257839Y77715D01*
G01D02*
X257790Y77442D01*
G01X257454Y75529D02*
X257405Y75255D01*
G01X257694Y76896D02*
X257646Y76622D01*
G01X257790Y77442D02*
X257741Y77169D01*
G01X258221Y79902D02*
X258174Y79628D01*
G01X258463Y81268D02*
X258414Y80995D01*
G01X258319Y80448D02*
X258270Y80175D01*
G01X258414Y80995D02*
X258367Y80721D01*
G01X261740Y74641D02*
X261691Y74368D01*
G01X261644Y74095D02*
X261596Y73822D01*
G01X262266Y77647D02*
X262219Y77373D01*
G01X261691Y74368D02*
X261644Y74095D01*
G01X262315Y77919D02*
X262266Y77647D01*
G01X262410Y78466D02*
X262362Y78193D01*
G01X261596Y73822D02*
X261547Y73548D01*
G01X262459Y78740D02*
X262410Y78466D01*
G01X262362Y78193D02*
X262315Y77919D01*
G01X261471Y73476D02*
X261535D01*
X261547Y73548D01*
G01X261979Y76007D02*
X261931Y75734D01*
G01X262075Y76554D02*
X262027Y76281D01*
G01D02*
X261979Y76007D01*
G01X262122Y76827D02*
X262075Y76554D01*
G01X262171Y77100D02*
X262122Y76827D01*
G01X261835Y75188D02*
X261787Y74914D01*
G01X262219Y77373D02*
X262171Y77100D01*
G01X261787Y74914D02*
X261740Y74641D01*
G01X261884Y75462D02*
X261835Y75188D01*
G01X261931Y75734D02*
X261884Y75462D01*
G01X262794Y80652D02*
X262746Y80378D01*
G01X262890Y81198D02*
X262841Y80925D01*
G01X262506Y79012D02*
X262459Y78740D01*
G01X260761Y73476D02*
X260999D01*
G01X260525D02*
X260761D01*
G01X260999D02*
X261235D01*
G01X262650Y79832D02*
X262602Y79558D01*
G01X262697Y80105D02*
X262650Y79832D01*
G01X262602Y79558D02*
X262554Y79285D01*
G01D02*
X262506Y79012D01*
G01X261235Y73476D02*
X261471D01*
G01X262841Y80925D02*
X262794Y80652D01*
G01X262746Y80378D02*
X262697Y80105D01*
G01X258221Y79902D02*
X258270Y80175D01*
G01X258367Y80721D02*
X258319Y80448D01*
G01X267742Y81308D02*
X277179Y90361D01*
G01X276943D02*
X267789Y81581D01*
G01X276706Y90361D02*
X267838Y81855D01*
G01X276468Y90361D02*
X267885Y82128D01*
G01X276231Y90361D02*
X267933Y82401D01*
G01X275995Y90361D02*
X267982Y82673D01*
G01X275758Y90361D02*
X268029Y82947D01*
G01X275520Y90361D02*
X268077Y83221D01*
G01X275284Y90361D02*
X268125Y83494D01*
G01X275047Y90361D02*
X268173Y83766D01*
G01X274811Y90361D02*
X268220Y84040D01*
G01X274573Y90361D02*
X268269Y84313D01*
G01X274336Y90361D02*
X268317Y84586D01*
G01X274100Y90361D02*
X268364Y84859D01*
G01X273863Y90361D02*
X268413Y85132D01*
G01X268460Y85406D02*
X273796Y90525D01*
G01X273845Y90798D02*
X268508Y85679D01*
G01X273893Y91071D02*
X268557Y85951D01*
G01Y86179D02*
X273940Y91344D01*
G01X268319Y86179D02*
X273989Y91618D01*
G01X268082Y86179D02*
X274036Y91891D01*
G01X267846Y86179D02*
X274085Y92164D01*
G01X267609Y86179D02*
X274133Y92438D01*
G01X267371Y86179D02*
X274182Y92711D01*
G01X267135Y86179D02*
X274229Y92984D01*
G01X266898Y86179D02*
X274276Y93257D01*
G01X266662Y86179D02*
X274325Y93531D01*
G01X266425Y86179D02*
X274373Y93805D01*
G01X266187Y86179D02*
X274420Y94077D01*
G01X265951Y86179D02*
X274469Y94350D01*
G01X265778Y86240D02*
X274517Y94624D01*
G01X274565Y94898D02*
X265825Y86514D01*
G01X274613Y95171D02*
X265874Y86787D01*
G01X274662Y95443D02*
X265921Y87060D01*
G01X274709Y95717D02*
X269369Y90595D01*
G01X265970Y87334D02*
X269125Y90361D01*
G01X274757Y95990D02*
X269418Y90868D01*
G01X266018Y87607D02*
X268889Y90361D01*
G01X274805Y96264D02*
X269466Y91142D01*
G01X266065Y87880D02*
X268652Y90361D01*
G01X266114Y88153D02*
X268416Y90361D01*
G01X274853Y96536D02*
X269513Y91414D01*
G01X274902Y96810D02*
X269562Y91688D01*
G01X266161Y88427D02*
X268178Y90361D01*
G01X266210Y88700D02*
X267941Y90361D01*
G01X258463Y81268D02*
X263403Y86006D01*
G01X274651Y96797D02*
X269609Y91961D01*
G01X274196Y96589D02*
X269658Y92234D01*
G01X266258Y88973D02*
X267705Y90361D01*
G01X258510Y81541D02*
X263397Y86228D01*
G01X273743Y96380D02*
X269706Y92507D01*
G01X266307Y89246D02*
X267468Y90361D01*
G01X258558Y81814D02*
X263362Y86422D01*
G01X258607Y82088D02*
X263327Y86616D01*
G01X267230Y90361D02*
X266354Y89520D01*
G01X273288Y96171D02*
X269753Y92781D01*
G01X272832Y95962D02*
X269802Y93055D01*
G01X263291Y86810D02*
X258656Y82361D01*
G01X266402Y89793D02*
X266994Y90361D01*
G01X266450Y90067D02*
X266757Y90361D01*
G01X263258Y87003D02*
X258702Y82633D01*
G01X272378Y95753D02*
X269849Y93327D01*
G01X266498Y90339D02*
X266521Y90361D01*
G01X271925Y95544D02*
X269897Y93600D01*
G01X263222Y87197D02*
X258734Y82892D01*
G01X263188Y87391D02*
X258769Y83152D01*
G01X271469Y95335D02*
X269946Y93874D01*
G01X271013Y95126D02*
X269993Y94147D01*
G01X263142Y87576D02*
X258802Y83412D01*
G01X263074Y87737D02*
X258833Y83668D01*
G01X270560Y94918D02*
X270042Y94420D01*
G01X263007Y87899D02*
X258835Y83897D01*
G01X270106Y94709D02*
X270089Y94693D01*
G01X262937Y88060D02*
X258837Y84127D01*
G01X262868Y88222D02*
X258840Y84356D01*
G01X262800Y88383D02*
X258829Y84573D01*
G01X262733Y88544D02*
X258797Y84769D01*
G01X262649Y88693D02*
X258764Y84965D01*
G01X262545Y88821D02*
X258731Y85161D01*
G01X262442Y88949D02*
X258665Y85325D01*
G01X262339Y89077D02*
X258596Y85485D01*
G01X262236Y89206D02*
X258525Y85645D01*
G01X262133Y89334D02*
X258430Y85783D01*
G01X262030Y89462D02*
X258322Y85905D01*
G01X261911Y89574D02*
X258213Y86028D01*
G01X261771Y89668D02*
X258086Y86133D01*
G01X261631Y89761D02*
X257937Y86217D01*
G01X261493Y89856D02*
X257790Y86303D01*
G01X261355Y89949D02*
X257623Y86370D01*
G01X261216Y90044D02*
X257438Y86419D01*
G01X261077Y90138D02*
X257250Y86468D01*
G01X260915Y90210D02*
X257047Y86499D01*
G01X260740Y90269D02*
X256826Y86514D01*
G01X260563Y90327D02*
X256605Y86529D01*
G01X260386Y90385D02*
X256362Y86524D01*
G01X260210Y90443D02*
X256107Y86506D01*
G01X260034Y90501D02*
X255851Y86487D01*
G01X259857Y90559D02*
X255535Y86412D01*
G01X266065Y87880D02*
X266114Y88153D01*
G01X266402Y89793D02*
X266450Y90067D01*
G01X266354Y89520D02*
X266307Y89246D01*
G01X268557Y86179D02*
X268596D01*
X268557Y85951D01*
G01X266402Y89793D02*
X266354Y89520D01*
G01X266161Y88427D02*
X266210Y88700D01*
G01X266258Y88973D02*
X266307Y89246D01*
G01X266210Y88700D02*
X266258Y88973D01*
G01X268460Y85406D02*
X268413Y85132D01*
G01X268652Y90361D02*
X268416D01*
G01X268889D02*
X268652D01*
G01X266018Y87607D02*
X266065Y87880D01*
G01X269125Y90361D02*
X268889D01*
G01X265970Y87334D02*
X266018Y87607D01*
G01X272216Y81511D02*
X272265Y81785D01*
G01X272169Y81237D02*
X272216Y81511D01*
G01X266114Y88153D02*
X266161Y88427D01*
G01X272265Y81785D02*
X272312Y82057D01*
G01X272409Y82604D02*
X272456Y82877D01*
G01X272312Y82057D02*
X272360Y82330D01*
G01D02*
X272409Y82604D01*
G01X268319Y86179D02*
X268557D01*
G01Y85951D02*
X268508Y85679D01*
G01D02*
X268460Y85406D01*
G01X268364Y84859D02*
X268317Y84586D01*
G01X268413Y85132D02*
X268364Y84859D01*
G01X267135Y86179D02*
X267371D01*
G01X266898D02*
X267135D01*
G01X266662D02*
X266898D01*
G01X267846D02*
X268082D01*
G01X267371D02*
X267609D01*
G01D02*
X267846D01*
G01X268317Y84586D02*
X268269Y84313D01*
G01X267838Y81855D02*
X267789Y81581D01*
G01X267933Y82401D02*
X267885Y82128D01*
G01D02*
X267838Y81855D01*
G01X267789Y81581D02*
X267742Y81308D01*
G01X267982Y82673D02*
X267933Y82401D01*
G01X268125Y83494D02*
X268077Y83221D01*
G01X268173Y83766D02*
X268125Y83494D01*
G01X268220Y84040D02*
X268173Y83766D01*
G01X268269Y84313D02*
X268220Y84040D01*
G01X268029Y82947D02*
X267982Y82673D01*
G01X268077Y83221D02*
X268029Y82947D01*
G01X268082Y86179D02*
X268319D01*
G01X269946Y93874D02*
X269897Y93600D01*
G01X269946Y93874D02*
X269993Y94147D01*
G01X269802Y93055D02*
X269753Y92781D01*
G01X269897Y93600D02*
X269849Y93327D01*
G01X269753Y92781D02*
X269706Y92507D01*
G01X269993Y94147D02*
X270042Y94420D01*
G01X269849Y93327D02*
X269802Y93055D01*
G01X266425Y86179D02*
X266662D01*
G01X270106Y94709D02*
X270091Y94702D01*
X270089Y94693D01*
G01X270042Y94420D02*
X270089Y94693D01*
G01X265874Y86787D02*
X265825Y86514D01*
G01X265921Y87060D02*
X265874Y86787D01*
G01X265825Y86514D02*
X265778Y86240D01*
G01X265921Y87060D02*
X265970Y87334D01*
G01X266187Y86179D02*
X266425D01*
G01X269706Y92507D02*
X269658Y92234D01*
G01X265778Y86240D02*
X265767Y86179D01*
X265951D01*
G01D02*
X266187D01*
G01X269562Y91688D02*
X269513Y91414D01*
G01X269609Y91961D02*
X269562Y91688D01*
G01X269658Y92234D02*
X269609Y91961D01*
G01X269418Y90868D02*
X269369Y90595D01*
G01X269125Y90361D02*
X269329D01*
X269369Y90595D01*
G01X269466Y91142D02*
X269418Y90868D01*
G01X269513Y91414D02*
X269466Y91142D01*
G01X268178Y90361D02*
X267941D01*
G01X268416D02*
X268178D01*
G01X271469Y95335D02*
X271013Y95126D01*
G01X272832Y95962D02*
X272378Y95753D01*
G01X266450Y90067D02*
X266498Y90339D01*
G01D02*
X266502Y90361D01*
X266521D01*
G01X270560Y94918D02*
X270106Y94709D01*
G01X271013Y95126D02*
X270560Y94918D01*
G01X266994Y90361D02*
X266757D01*
G01D02*
X266521D01*
G01X267705D02*
X267468D01*
G01X272378Y95753D02*
X271925Y95544D01*
G01X267941Y90361D02*
X267705D01*
G01X266994D02*
X267230D01*
G01D02*
X267468D01*
G01X271925Y95544D02*
X271469Y95335D01*
G01X258656Y82361D02*
X258607Y82088D01*
G01X263081Y82291D02*
X263034Y82018D01*
G01X263129Y82563D02*
X263081Y82291D01*
G01X258607Y82088D02*
X258558Y81814D01*
G01X262985Y81744D02*
X262937Y81471D01*
G01D02*
X262890Y81198D01*
G01X263034Y82018D02*
X262985Y81744D01*
G01X258510Y81541D02*
X258463Y81268D01*
G01X263178Y82837D02*
X263129Y82563D01*
G01X258558Y81814D02*
X258510Y81541D01*
G01X267742Y81308D02*
X277179Y90361D01*
G01X276943D02*
X267789Y81581D01*
G01X276706Y90361D02*
X267838Y81855D01*
G01X276468Y90361D02*
X267885Y82128D01*
G01X276231Y90361D02*
X267933Y82401D01*
G01X275995Y90361D02*
X267982Y82673D01*
G01X275758Y90361D02*
X268029Y82947D01*
G01X275520Y90361D02*
X268077Y83221D01*
G01X275284Y90361D02*
X268125Y83494D01*
G01X275047Y90361D02*
X268173Y83766D01*
G01X274811Y90361D02*
X268220Y84040D01*
G01X274573Y90361D02*
X268269Y84313D01*
G01X274336Y90361D02*
X268317Y84586D01*
G01X274100Y90361D02*
X268364Y84859D01*
G01X273863Y90361D02*
X268413Y85132D01*
G01X268460Y85406D02*
X273796Y90525D01*
G01X273845Y90798D02*
X268508Y85679D01*
G01X273893Y91071D02*
X268557Y85951D01*
G01Y86179D02*
X273940Y91344D01*
G01X268319Y86179D02*
X273989Y91618D01*
G01X268082Y86179D02*
X274036Y91891D01*
G01X267846Y86179D02*
X274085Y92164D01*
G01X267609Y86179D02*
X274133Y92438D01*
G01X267371Y86179D02*
X274182Y92711D01*
G01X267135Y86179D02*
X274229Y92984D01*
G01X266898Y86179D02*
X274276Y93257D01*
G01X266662Y86179D02*
X274325Y93531D01*
G01X266425Y86179D02*
X274373Y93805D01*
G01X266187Y86179D02*
X274420Y94077D01*
G01X265951Y86179D02*
X274469Y94350D01*
G01X265778Y86240D02*
X274517Y94624D01*
G01X274565Y94898D02*
X265825Y86514D01*
G01X274613Y95171D02*
X265874Y86787D01*
G01X274662Y95443D02*
X265921Y87060D01*
G01X274709Y95717D02*
X269369Y90595D01*
G01X265970Y87334D02*
X269125Y90361D01*
G01X274757Y95990D02*
X269418Y90868D01*
G01X266018Y87607D02*
X268889Y90361D01*
G01X274805Y96264D02*
X269466Y91142D01*
G01X266065Y87880D02*
X268652Y90361D01*
G01X266114Y88153D02*
X268416Y90361D01*
G01X274853Y96536D02*
X269513Y91414D01*
G01X274902Y96810D02*
X269562Y91688D01*
G01X266161Y88427D02*
X268178Y90361D01*
G01X266210Y88700D02*
X267941Y90361D01*
G01X258463Y81268D02*
X263403Y86006D01*
G01X274651Y96797D02*
X269609Y91961D01*
G01X274196Y96589D02*
X269658Y92234D01*
G01X266258Y88973D02*
X267705Y90361D01*
G01X258510Y81541D02*
X263397Y86228D01*
G01X273743Y96380D02*
X269706Y92507D01*
G01X266307Y89246D02*
X267468Y90361D01*
G01X258558Y81814D02*
X263362Y86422D01*
G01X258607Y82088D02*
X263327Y86616D01*
G01X267230Y90361D02*
X266354Y89520D01*
G01X273288Y96171D02*
X269753Y92781D01*
G01X272832Y95962D02*
X269802Y93055D01*
G01X263291Y86810D02*
X258656Y82361D01*
G01X266402Y89793D02*
X266994Y90361D01*
G01X266450Y90067D02*
X266757Y90361D01*
G01X263258Y87003D02*
X258702Y82633D01*
G01X272378Y95753D02*
X269849Y93327D01*
G01X266498Y90339D02*
X266521Y90361D01*
G01X271925Y95544D02*
X269897Y93600D01*
G01X263222Y87197D02*
X258734Y82892D01*
G01X263188Y87391D02*
X258769Y83152D01*
G01X271469Y95335D02*
X269946Y93874D01*
G01X271013Y95126D02*
X269993Y94147D01*
G01X263142Y87576D02*
X258802Y83412D01*
G01X263074Y87737D02*
X258833Y83668D01*
G01X270560Y94918D02*
X270042Y94420D01*
G01X263007Y87899D02*
X258835Y83897D01*
G01X270106Y94709D02*
X270089Y94693D01*
G01X262937Y88060D02*
X258837Y84127D01*
G01X262868Y88222D02*
X258840Y84356D01*
G01X262800Y88383D02*
X258829Y84573D01*
G01X262733Y88544D02*
X258797Y84769D01*
G01X262649Y88693D02*
X258764Y84965D01*
G01X262545Y88821D02*
X258731Y85161D01*
G01X262442Y88949D02*
X258665Y85325D01*
G01X262339Y89077D02*
X258596Y85485D01*
G01X262236Y89206D02*
X258525Y85645D01*
G01X262133Y89334D02*
X258430Y85783D01*
G01X262030Y89462D02*
X258322Y85905D01*
G01X261911Y89574D02*
X258213Y86028D01*
G01X261771Y89668D02*
X258086Y86133D01*
G01X261631Y89761D02*
X257937Y86217D01*
G01X261493Y89856D02*
X257790Y86303D01*
G01X261355Y89949D02*
X257623Y86370D01*
G01X261216Y90044D02*
X257438Y86419D01*
G01X261077Y90138D02*
X257250Y86468D01*
G01X260915Y90210D02*
X257047Y86499D01*
G01X260740Y90269D02*
X256826Y86514D01*
G01X260563Y90327D02*
X256605Y86529D01*
G01X260386Y90385D02*
X256362Y86524D01*
G01X260210Y90443D02*
X256107Y86506D01*
G01X260034Y90501D02*
X255851Y86487D01*
G01X259857Y90559D02*
X255535Y86412D01*
G01X266065Y87880D02*
X266114Y88153D01*
G01X266402Y89793D02*
X266450Y90067D01*
G01X266354Y89520D02*
X266307Y89246D01*
G01X268557Y86179D02*
X268596D01*
X268557Y85951D01*
G01X266402Y89793D02*
X266354Y89520D01*
G01X266161Y88427D02*
X266210Y88700D01*
G01X266258Y88973D02*
X266307Y89246D01*
G01X266210Y88700D02*
X266258Y88973D01*
G01X268460Y85406D02*
X268413Y85132D01*
G01X268652Y90361D02*
X268416D01*
G01X268889D02*
X268652D01*
G01X266018Y87607D02*
X266065Y87880D01*
G01X269125Y90361D02*
X268889D01*
G01X265970Y87334D02*
X266018Y87607D01*
G01X272216Y81511D02*
X272265Y81785D01*
G01X272169Y81237D02*
X272216Y81511D01*
G01X266114Y88153D02*
X266161Y88427D01*
G01X272265Y81785D02*
X272312Y82057D01*
G01X272409Y82604D02*
X272456Y82877D01*
G01X272312Y82057D02*
X272360Y82330D01*
G01D02*
X272409Y82604D01*
G01X268319Y86179D02*
X268557D01*
G01Y85951D02*
X268508Y85679D01*
G01D02*
X268460Y85406D01*
G01X268364Y84859D02*
X268317Y84586D01*
G01X268413Y85132D02*
X268364Y84859D01*
G01X267135Y86179D02*
X267371D01*
G01X266898D02*
X267135D01*
G01X266662D02*
X266898D01*
G01X267846D02*
X268082D01*
G01X267371D02*
X267609D01*
G01D02*
X267846D01*
G01X268317Y84586D02*
X268269Y84313D01*
G01X267838Y81855D02*
X267789Y81581D01*
G01X267933Y82401D02*
X267885Y82128D01*
G01D02*
X267838Y81855D01*
G01X267789Y81581D02*
X267742Y81308D01*
G01X267982Y82673D02*
X267933Y82401D01*
G01X268125Y83494D02*
X268077Y83221D01*
G01X268173Y83766D02*
X268125Y83494D01*
G01X268220Y84040D02*
X268173Y83766D01*
G01X268269Y84313D02*
X268220Y84040D01*
G01X268029Y82947D02*
X267982Y82673D01*
G01X268077Y83221D02*
X268029Y82947D01*
G01X268082Y86179D02*
X268319D01*
G01X269946Y93874D02*
X269897Y93600D01*
G01X269946Y93874D02*
X269993Y94147D01*
G01X269802Y93055D02*
X269753Y92781D01*
G01X269897Y93600D02*
X269849Y93327D01*
G01X269753Y92781D02*
X269706Y92507D01*
G01X269993Y94147D02*
X270042Y94420D01*
G01X269849Y93327D02*
X269802Y93055D01*
G01X266425Y86179D02*
X266662D01*
G01X270106Y94709D02*
X270091Y94702D01*
X270089Y94693D01*
G01X270042Y94420D02*
X270089Y94693D01*
G01X265874Y86787D02*
X265825Y86514D01*
G01X265921Y87060D02*
X265874Y86787D01*
G01X265825Y86514D02*
X265778Y86240D01*
G01X265921Y87060D02*
X265970Y87334D01*
G01X266187Y86179D02*
X266425D01*
G01X269706Y92507D02*
X269658Y92234D01*
G01X265778Y86240D02*
X265767Y86179D01*
X265951D01*
G01D02*
X266187D01*
G01X269562Y91688D02*
X269513Y91414D01*
G01X269609Y91961D02*
X269562Y91688D01*
G01X269658Y92234D02*
X269609Y91961D01*
G01X269418Y90868D02*
X269369Y90595D01*
G01X269125Y90361D02*
X269329D01*
X269369Y90595D01*
G01X269466Y91142D02*
X269418Y90868D01*
G01X269513Y91414D02*
X269466Y91142D01*
G01X268178Y90361D02*
X267941D01*
G01X268416D02*
X268178D01*
G01X271469Y95335D02*
X271013Y95126D01*
G01X272832Y95962D02*
X272378Y95753D01*
G01X266450Y90067D02*
X266498Y90339D01*
G01D02*
X266502Y90361D01*
X266521D01*
G01X270560Y94918D02*
X270106Y94709D01*
G01X271013Y95126D02*
X270560Y94918D01*
G01X266994Y90361D02*
X266757D01*
G01D02*
X266521D01*
G01X267705D02*
X267468D01*
G01X272378Y95753D02*
X271925Y95544D01*
G01X267941Y90361D02*
X267705D01*
G01X266994D02*
X267230D01*
G01D02*
X267468D01*
G01X271925Y95544D02*
X271469Y95335D01*
G01X258656Y82361D02*
X258607Y82088D01*
G01X263081Y82291D02*
X263034Y82018D01*
G01X263129Y82563D02*
X263081Y82291D01*
G01X258607Y82088D02*
X258558Y81814D01*
G01X262985Y81744D02*
X262937Y81471D01*
G01D02*
X262890Y81198D01*
G01X263034Y82018D02*
X262985Y81744D01*
G01X258510Y81541D02*
X258463Y81268D01*
G01X263178Y82837D02*
X263129Y82563D01*
G01X258558Y81814D02*
X258510Y81541D01*
G01X268819Y281339D02*
G02Y273071I0J-4134D01*
G02Y281339I0J4134D01*
G01X253819D02*
G02Y273071I0J-4134D01*
G02Y281339I0J4134D01*
G01X268819Y273071D02*
G03Y281339I0J4134D01*
G03Y273071I0J-4134D01*
G01X253819D02*
G03Y281339I0J4134D01*
G03Y273071I0J-4134D01*
G01Y480354D02*
G02Y474055I0J-3149D01*
G02Y480354I0J3149D01*
G01Y474055D02*
G03Y480354I0J3149D01*
G03Y474055I0J-3149D01*
G01X291553Y73476D02*
X291636Y73556D01*
G01X291316Y73476D02*
X291685Y73830D01*
G01X291079Y73476D02*
X291733Y74104D01*
G01X290843Y73476D02*
X291780Y74376D01*
G01X290605Y73476D02*
X291827Y74648D01*
G01X290368Y73476D02*
X291876Y74922D01*
G01X290131Y73476D02*
X291924Y75196D01*
G01X289895Y73476D02*
X291971Y75468D01*
G01X289659Y73476D02*
X292020Y75741D01*
G01X289421Y73476D02*
X292068Y76015D01*
G01X289184Y73476D02*
X292115Y76289D01*
G01X288947Y73476D02*
X292164Y76561D01*
G01X288711Y73476D02*
X292211Y76834D01*
G01X288473Y73476D02*
X292259Y77107D01*
G01X288236Y73476D02*
X292308Y77381D01*
G01X288000Y73476D02*
X292355Y77653D01*
G01X287764Y73476D02*
X292403Y77926D01*
G01X287527Y73476D02*
X292450Y78200D01*
G01X287289Y73476D02*
X292499Y78473D01*
G01X287212Y73628D02*
X292546Y78746D01*
G01X287259Y73902D02*
X292594Y79019D01*
G01X287308Y74175D02*
X292643Y79293D01*
G01X292690Y79566D02*
X287356Y74449D01*
G01X286972Y74308D02*
X292738Y79838D01*
G01X286298Y73888D02*
X292785Y80111D01*
G01X285824Y73661D02*
X292834Y80385D01*
G01X285419Y73499D02*
X292881Y80658D01*
G01X285082Y73404D02*
X292929Y80931D01*
G01X284746Y73308D02*
X292978Y81204D01*
G01X284427Y73230D02*
X293025Y81478D01*
G01X284163Y73203D02*
X293073Y81751D01*
G01X283900Y73179D02*
X293120Y82024D01*
G01X283637Y73152D02*
X293169Y82296D01*
G01X283372Y73127D02*
X293216Y82570D01*
G01X283139Y73130D02*
X293264Y82843D01*
G01X282911Y73138D02*
X293313Y83116D01*
G01X293360Y83389D02*
X282688Y73152D01*
G01X293408Y83663D02*
X288074Y78547D01*
G01X282477Y73176D02*
X287114Y77625D01*
G01X282267Y73202D02*
X286542Y77303D01*
G01X293456Y83936D02*
X288122Y78820D01*
G01X293504Y84209D02*
X288171Y79092D01*
G01X282065Y73234D02*
X286161Y77164D01*
G01X293551Y84481D02*
X288218Y79365D01*
G01X281869Y73274D02*
X285780Y77025D01*
G01X293599Y84755D02*
X288266Y79639D01*
G01X281674Y73314D02*
X285497Y76983D01*
G01X293625Y85006D02*
X288315Y79912D01*
G01X281488Y73365D02*
X285225Y76949D01*
G01X293644Y85252D02*
X288362Y80185D01*
G01X281308Y73418D02*
X284954Y76916D01*
G01X281127Y73472D02*
X284685Y76885D01*
G01X293664Y85498D02*
X288409Y80458D01*
G01X280958Y73537D02*
X284465Y76901D01*
G01X293684Y85745D02*
X288334Y80612D01*
G01X280791Y73605D02*
X284246Y76918D01*
G01X293705Y85993D02*
X288191Y80704D01*
G01X280624Y73672D02*
X284029Y76937D01*
G01X293706Y86221D02*
X288042Y80787D01*
G01X280468Y73749D02*
X283843Y76986D01*
G01X293679Y86421D02*
X287890Y80868D01*
G01X280315Y73830D02*
X283657Y77034D01*
G01X293652Y86623D02*
X287725Y80937D01*
G01X280163Y73911D02*
X283479Y77093D01*
G01X293623Y86824D02*
X287555Y81002D01*
G01X280018Y73999D02*
X283327Y77173D01*
G01X293596Y87024D02*
X287376Y81057D01*
G01X279881Y74093D02*
X283174Y77253D01*
G01X279741Y74188D02*
X283041Y77354D01*
G01X279608Y74288D02*
X282922Y77466D01*
G01X279485Y74395D02*
X282805Y77582D01*
G01X279360Y74503D02*
X282718Y77725D01*
G01X279238Y74614D02*
X282633Y77870D01*
G01X279128Y74736D02*
X282573Y78041D01*
G01X279020Y74858D02*
X282522Y78218D01*
G01X278910Y74981D02*
X282493Y78417D01*
G01X278815Y75116D02*
X282477Y78630D01*
G01X278720Y75253D02*
X282489Y78869D01*
G01X278626Y75390D02*
X282515Y79120D01*
G01X278543Y75538D02*
X282633Y79461D01*
G01X278466Y75691D02*
X282759Y79809D01*
G01X283925Y80928D02*
X287699Y84548D01*
G01X278389Y75844D02*
X283421Y80672D01*
G01X283460Y80709D02*
X287498Y84583D01*
G01X278318Y76004D02*
X287299Y84618D01*
G01X278259Y76174D02*
X287098Y84653D01*
G01X278199Y76344D02*
X286889Y84681D01*
G01X278145Y76519D02*
X286665Y84692D01*
G01X278104Y76707D02*
X286440Y84704D01*
G01X278065Y76895D02*
X286216Y84716D01*
G01X278027Y77086D02*
X285993Y84728D01*
G01X278008Y77296D02*
X285748Y84722D01*
G01X277989Y77505D02*
X285496Y84706D01*
G01X274013Y73919D02*
X274506Y74391D01*
G01X285242Y84691D02*
X277971Y77715D01*
G01X273529Y73681D02*
X274610Y74719D01*
G01X277977Y77948D02*
X284989Y84674D01*
G01X277982Y78180D02*
X284735Y84659D01*
G01X273143Y73538D02*
X274715Y75046D01*
G01X277989Y78414D02*
X284479Y84640D01*
G01X272771Y73408D02*
X274818Y75373D01*
G01X272463Y73339D02*
X274922Y75699D01*
G01X278021Y78673D02*
X284182Y84582D01*
G01X278055Y78932D02*
X283883Y84523D01*
G01X278099Y79202D02*
X283585Y84464D01*
G01X278185Y79512D02*
X283288Y84406D01*
G01X278272Y79822D02*
X282945Y84305D01*
G01X278360Y80133D02*
X282570Y84173D01*
G01X278447Y80444D02*
X282196Y84040D01*
G01X278682Y80897D02*
X281773Y83863D01*
G01X290368Y73476D02*
X290605D01*
G01X289895D02*
X290131D01*
G01D02*
X290368D01*
G01X289421D02*
X289659D01*
G01D02*
X289895D01*
G01X291316D02*
X291553D01*
G01D02*
X291623D01*
X291636Y73556D01*
G01X289184Y73476D02*
X289421D01*
G01X290605D02*
X290843D01*
G01X291079D02*
X291316D01*
G01X290843D02*
X291079D01*
G01X287289D02*
X287527D01*
G01X287308Y74175D02*
X287259Y73902D01*
G01X287212Y73628D02*
X287185Y73476D01*
X287289D01*
G01X287259Y73902D02*
X287212Y73628D01*
G01X288711Y73476D02*
X288947D01*
G01X288473D02*
X288711D01*
G01X288947D02*
X289184D01*
G01X287764D02*
X288000D01*
G01D02*
X288236D01*
G01D02*
X288473D01*
G01X292643Y79293D02*
X292690Y79566D01*
G01D02*
X292738Y79838D01*
G01D02*
X292785Y80111D01*
G01X292546Y78746D02*
X292594Y79019D01*
G01X292499Y78473D02*
X292546Y78746D01*
G01X292594Y79019D02*
X292643Y79293D01*
G01X292450Y78200D02*
X292499Y78473D01*
G01X292929Y80931D02*
X292978Y81204D01*
G01X291636Y73556D02*
X291685Y73830D01*
G01X292881Y80658D02*
X292929Y80931D01*
G01X292785Y80111D02*
X292834Y80385D01*
G01D02*
X292881Y80658D01*
G01X291827Y74648D02*
X291876Y74922D01*
G01X292403Y77926D02*
X292450Y78200D01*
G01X291924Y75196D02*
X291971Y75468D01*
G01X291876Y74922D02*
X291924Y75196D01*
G01X291780Y74376D02*
X291827Y74648D01*
G01X291685Y73830D02*
X291733Y74104D01*
G01D02*
X291780Y74376D01*
G01X292259Y77107D02*
X292308Y77381D01*
G01X292355Y77653D02*
X292403Y77926D01*
G01X292211Y76834D02*
X292259Y77107D01*
G01X292308Y77381D02*
X292355Y77653D01*
G01X292020Y75741D02*
X292068Y76015D01*
G01X291971Y75468D02*
X292020Y75741D01*
G01X292068Y76015D02*
X292115Y76289D01*
G01D02*
X292164Y76561D01*
G01D02*
X292211Y76834D01*
G01X287527Y73476D02*
X287764D01*
G01X288315Y79912D02*
X288266Y79639D01*
G01D02*
X288218Y79365D01*
G01X288409Y80458D02*
X288362Y80185D01*
G01D02*
X288315Y79912D01*
G01X288122Y78820D02*
X288074Y78547D01*
G01X288218Y79365D02*
X288171Y79092D01*
G01D02*
X288122Y78820D01*
G01X287356Y74449D02*
X287308Y74175D01*
G01X275234Y76680D02*
X275131Y76354D01*
G01X275338Y77007D02*
X275234Y76680D01*
G01X275131Y76354D02*
X275027Y76026D01*
G01X275442Y77334D02*
X275338Y77007D01*
G01X275027Y76026D02*
X274922Y75699D01*
G01X275546Y77662D02*
X275442Y77334D01*
G01X274922Y75699D02*
X274818Y75373D01*
G01D02*
X274715Y75046D01*
G01D02*
X274610Y74719D01*
G01X275650Y77988D02*
X275546Y77662D01*
G01X275754Y78315D02*
X275650Y77988D01*
G01X275858Y78642D02*
X275754Y78315D01*
G01X274610Y74719D02*
X274506Y74391D01*
G01X291553Y73476D02*
X291636Y73556D01*
G01X291316Y73476D02*
X291685Y73830D01*
G01X291079Y73476D02*
X291733Y74104D01*
G01X290843Y73476D02*
X291780Y74376D01*
G01X290605Y73476D02*
X291827Y74648D01*
G01X290368Y73476D02*
X291876Y74922D01*
G01X290131Y73476D02*
X291924Y75196D01*
G01X289895Y73476D02*
X291971Y75468D01*
G01X289659Y73476D02*
X292020Y75741D01*
G01X289421Y73476D02*
X292068Y76015D01*
G01X289184Y73476D02*
X292115Y76289D01*
G01X288947Y73476D02*
X292164Y76561D01*
G01X288711Y73476D02*
X292211Y76834D01*
G01X288473Y73476D02*
X292259Y77107D01*
G01X288236Y73476D02*
X292308Y77381D01*
G01X288000Y73476D02*
X292355Y77653D01*
G01X287764Y73476D02*
X292403Y77926D01*
G01X287527Y73476D02*
X292450Y78200D01*
G01X287289Y73476D02*
X292499Y78473D01*
G01X287212Y73628D02*
X292546Y78746D01*
G01X287259Y73902D02*
X292594Y79019D01*
G01X287308Y74175D02*
X292643Y79293D01*
G01X292690Y79566D02*
X287356Y74449D01*
G01X286972Y74308D02*
X292738Y79838D01*
G01X286298Y73888D02*
X292785Y80111D01*
G01X285824Y73661D02*
X292834Y80385D01*
G01X285419Y73499D02*
X292881Y80658D01*
G01X285082Y73404D02*
X292929Y80931D01*
G01X284746Y73308D02*
X292978Y81204D01*
G01X284427Y73230D02*
X293025Y81478D01*
G01X284163Y73203D02*
X293073Y81751D01*
G01X283900Y73179D02*
X293120Y82024D01*
G01X283637Y73152D02*
X293169Y82296D01*
G01X283372Y73127D02*
X293216Y82570D01*
G01X283139Y73130D02*
X293264Y82843D01*
G01X282911Y73138D02*
X293313Y83116D01*
G01X293360Y83389D02*
X282688Y73152D01*
G01X293408Y83663D02*
X288074Y78547D01*
G01X282477Y73176D02*
X287114Y77625D01*
G01X282267Y73202D02*
X286542Y77303D01*
G01X293456Y83936D02*
X288122Y78820D01*
G01X293504Y84209D02*
X288171Y79092D01*
G01X282065Y73234D02*
X286161Y77164D01*
G01X293551Y84481D02*
X288218Y79365D01*
G01X281869Y73274D02*
X285780Y77025D01*
G01X293599Y84755D02*
X288266Y79639D01*
G01X281674Y73314D02*
X285497Y76983D01*
G01X293625Y85006D02*
X288315Y79912D01*
G01X281488Y73365D02*
X285225Y76949D01*
G01X293644Y85252D02*
X288362Y80185D01*
G01X281308Y73418D02*
X284954Y76916D01*
G01X281127Y73472D02*
X284685Y76885D01*
G01X293664Y85498D02*
X288409Y80458D01*
G01X280958Y73537D02*
X284465Y76901D01*
G01X293684Y85745D02*
X288334Y80612D01*
G01X280791Y73605D02*
X284246Y76918D01*
G01X293705Y85993D02*
X288191Y80704D01*
G01X280624Y73672D02*
X284029Y76937D01*
G01X293706Y86221D02*
X288042Y80787D01*
G01X280468Y73749D02*
X283843Y76986D01*
G01X293679Y86421D02*
X287890Y80868D01*
G01X280315Y73830D02*
X283657Y77034D01*
G01X293652Y86623D02*
X287725Y80937D01*
G01X280163Y73911D02*
X283479Y77093D01*
G01X293623Y86824D02*
X287555Y81002D01*
G01X280018Y73999D02*
X283327Y77173D01*
G01X293596Y87024D02*
X287376Y81057D01*
G01X279881Y74093D02*
X283174Y77253D01*
G01X279741Y74188D02*
X283041Y77354D01*
G01X279608Y74288D02*
X282922Y77466D01*
G01X279485Y74395D02*
X282805Y77582D01*
G01X279360Y74503D02*
X282718Y77725D01*
G01X279238Y74614D02*
X282633Y77870D01*
G01X279128Y74736D02*
X282573Y78041D01*
G01X279020Y74858D02*
X282522Y78218D01*
G01X278910Y74981D02*
X282493Y78417D01*
G01X278815Y75116D02*
X282477Y78630D01*
G01X278720Y75253D02*
X282489Y78869D01*
G01X278626Y75390D02*
X282515Y79120D01*
G01X278543Y75538D02*
X282633Y79461D01*
G01X278466Y75691D02*
X282759Y79809D01*
G01X283925Y80928D02*
X287699Y84548D01*
G01X278389Y75844D02*
X283421Y80672D01*
G01X283460Y80709D02*
X287498Y84583D01*
G01X278318Y76004D02*
X287299Y84618D01*
G01X278259Y76174D02*
X287098Y84653D01*
G01X278199Y76344D02*
X286889Y84681D01*
G01X278145Y76519D02*
X286665Y84692D01*
G01X278104Y76707D02*
X286440Y84704D01*
G01X278065Y76895D02*
X286216Y84716D01*
G01X278027Y77086D02*
X285993Y84728D01*
G01X278008Y77296D02*
X285748Y84722D01*
G01X277989Y77505D02*
X285496Y84706D01*
G01X274013Y73919D02*
X274506Y74391D01*
G01X285242Y84691D02*
X277971Y77715D01*
G01X273529Y73681D02*
X274610Y74719D01*
G01X277977Y77948D02*
X284989Y84674D01*
G01X277982Y78180D02*
X284735Y84659D01*
G01X273143Y73538D02*
X274715Y75046D01*
G01X277989Y78414D02*
X284479Y84640D01*
G01X272771Y73408D02*
X274818Y75373D01*
G01X272463Y73339D02*
X274922Y75699D01*
G01X278021Y78673D02*
X284182Y84582D01*
G01X278055Y78932D02*
X283883Y84523D01*
G01X278099Y79202D02*
X283585Y84464D01*
G01X278185Y79512D02*
X283288Y84406D01*
G01X278272Y79822D02*
X282945Y84305D01*
G01X278360Y80133D02*
X282570Y84173D01*
G01X278447Y80444D02*
X282196Y84040D01*
G01X278682Y80897D02*
X281773Y83863D01*
G01X290368Y73476D02*
X290605D01*
G01X289895D02*
X290131D01*
G01D02*
X290368D01*
G01X289421D02*
X289659D01*
G01D02*
X289895D01*
G01X291316D02*
X291553D01*
G01D02*
X291623D01*
X291636Y73556D01*
G01X289184Y73476D02*
X289421D01*
G01X290605D02*
X290843D01*
G01X291079D02*
X291316D01*
G01X290843D02*
X291079D01*
G01X287289D02*
X287527D01*
G01X287308Y74175D02*
X287259Y73902D01*
G01X287212Y73628D02*
X287185Y73476D01*
X287289D01*
G01X287259Y73902D02*
X287212Y73628D01*
G01X288711Y73476D02*
X288947D01*
G01X288473D02*
X288711D01*
G01X288947D02*
X289184D01*
G01X287764D02*
X288000D01*
G01D02*
X288236D01*
G01D02*
X288473D01*
G01X292643Y79293D02*
X292690Y79566D01*
G01D02*
X292738Y79838D01*
G01D02*
X292785Y80111D01*
G01X292546Y78746D02*
X292594Y79019D01*
G01X292499Y78473D02*
X292546Y78746D01*
G01X292594Y79019D02*
X292643Y79293D01*
G01X292450Y78200D02*
X292499Y78473D01*
G01X292929Y80931D02*
X292978Y81204D01*
G01X291636Y73556D02*
X291685Y73830D01*
G01X292881Y80658D02*
X292929Y80931D01*
G01X292785Y80111D02*
X292834Y80385D01*
G01D02*
X292881Y80658D01*
G01X291827Y74648D02*
X291876Y74922D01*
G01X292403Y77926D02*
X292450Y78200D01*
G01X291924Y75196D02*
X291971Y75468D01*
G01X291876Y74922D02*
X291924Y75196D01*
G01X291780Y74376D02*
X291827Y74648D01*
G01X291685Y73830D02*
X291733Y74104D01*
G01D02*
X291780Y74376D01*
G01X292259Y77107D02*
X292308Y77381D01*
G01X292355Y77653D02*
X292403Y77926D01*
G01X292211Y76834D02*
X292259Y77107D01*
G01X292308Y77381D02*
X292355Y77653D01*
G01X292020Y75741D02*
X292068Y76015D01*
G01X291971Y75468D02*
X292020Y75741D01*
G01X292068Y76015D02*
X292115Y76289D01*
G01D02*
X292164Y76561D01*
G01D02*
X292211Y76834D01*
G01X287527Y73476D02*
X287764D01*
G01X288315Y79912D02*
X288266Y79639D01*
G01D02*
X288218Y79365D01*
G01X288409Y80458D02*
X288362Y80185D01*
G01D02*
X288315Y79912D01*
G01X288122Y78820D02*
X288074Y78547D01*
G01X288218Y79365D02*
X288171Y79092D01*
G01D02*
X288122Y78820D01*
G01X287356Y74449D02*
X287308Y74175D01*
G01X275234Y76680D02*
X275131Y76354D01*
G01X275338Y77007D02*
X275234Y76680D01*
G01X275131Y76354D02*
X275027Y76026D01*
G01X275442Y77334D02*
X275338Y77007D01*
G01X275027Y76026D02*
X274922Y75699D01*
G01X275546Y77662D02*
X275442Y77334D01*
G01X274922Y75699D02*
X274818Y75373D01*
G01D02*
X274715Y75046D01*
G01D02*
X274610Y74719D01*
G01X275650Y77988D02*
X275546Y77662D01*
G01X275754Y78315D02*
X275650Y77988D01*
G01X275858Y78642D02*
X275754Y78315D01*
G01X274610Y74719D02*
X274506Y74391D01*
G01X293569Y87225D02*
X287190Y81105D01*
G01X293522Y87407D02*
X286995Y81146D01*
G01X293454Y87570D02*
X286791Y81179D01*
G01X293387Y87732D02*
X286584Y81206D01*
G01X293321Y87895D02*
X286368Y81225D01*
G01X293254Y88059D02*
X286146Y81240D01*
G01X293187Y88222D02*
X289081Y84283D01*
G01X288909Y84119D02*
X285919Y81251D01*
G01X293109Y88375D02*
X289130Y84557D01*
G01X288750Y84194D02*
X285689Y81256D01*
G01X288591Y84268D02*
X285455Y81259D01*
G01X293009Y88505D02*
X289177Y84830D01*
G01X288424Y84335D02*
X285183Y81225D01*
G01X292907Y88635D02*
X289206Y85085D01*
G01X288245Y84392D02*
X284909Y81191D01*
G01X292805Y88766D02*
X289227Y85332D01*
G01X284638Y81157D02*
X288068Y84447D01*
G01X292705Y88895D02*
X289206Y85538D01*
G01X284365Y81123D02*
X287890Y84504D01*
G01X292603Y89025D02*
X289181Y85743D01*
G01X292502Y89156D02*
X289123Y85914D01*
G01X292375Y89261D02*
X289065Y86086D01*
G01X292243Y89361D02*
X288976Y86228D01*
G01X292111Y89461D02*
X288886Y86367D01*
G01X291978Y89561D02*
X288774Y86488D01*
G01X291845Y89662D02*
X288651Y86598D01*
G01X291714Y89761D02*
X288521Y86700D01*
G01X291575Y89856D02*
X288369Y86780D01*
G01X291412Y89928D02*
X288214Y86860D01*
G01X291250Y90000D02*
X288037Y86917D01*
G01X291088Y90071D02*
X287852Y86967D01*
G01X290927Y90143D02*
X287658Y87008D01*
G01X290764Y90215D02*
X287438Y87025D01*
G01X290603Y90287D02*
X287220Y87043D01*
G01X290425Y90345D02*
X286985Y87044D01*
G01X290235Y90388D02*
X286744Y87039D01*
G01X290044Y90432D02*
X286501Y87035D01*
G01X289851Y90476D02*
X286250Y87021D01*
G01X289661Y90520D02*
X285995Y87003D01*
G01X289470Y90564D02*
X285738Y86984D01*
G01X289279Y90608D02*
X285464Y86948D01*
G01X289062Y90627D02*
X285190Y86913D01*
G01X288841Y90642D02*
X284893Y86854D01*
G01X278921Y81352D02*
X281224Y83562D01*
G01X288621Y90657D02*
X284591Y86792D01*
G01X288399Y90673D02*
X284258Y86700D01*
G01X283908Y86591D02*
X288178Y90688D01*
G01X283533Y86459D02*
X287956Y90703D01*
G01X283117Y86287D02*
X287730Y90712D01*
G01X282668Y86084D02*
X287486Y90705D01*
G01X282309Y85966D02*
X287242Y90699D01*
G01X282245Y86133D02*
X286998Y90692D01*
G01X282183Y86299D02*
X286749Y90681D01*
G01X282120Y86467D02*
X286489Y90657D01*
G01X282056Y86634D02*
X286227Y90634D01*
G01X281994Y86801D02*
X285965Y90611D01*
G01X281932Y86967D02*
X285687Y90570D01*
G01X281868Y87134D02*
X285404Y90525D01*
G01X281805Y87302D02*
X285119Y90480D01*
G01X281743Y87468D02*
X284811Y90412D01*
G01X281679Y87635D02*
X284499Y90339D01*
G01X281617Y87802D02*
X284176Y90257D01*
G01X281555Y87969D02*
X283825Y90148D01*
G01X281491Y88136D02*
X283474Y90038D01*
G01X281428Y88303D02*
X283080Y89887D01*
G01X281366Y88470D02*
X282680Y89730D01*
G01X281302Y88637D02*
X282234Y89531D01*
G01X281240Y88804D02*
X281772Y89314D01*
G01X281178Y88970D02*
X281277Y89066D01*
G01X277090Y86185D02*
X277083Y86179D01*
G01X277137Y86459D02*
X276845Y86179D01*
G01X277184Y86731D02*
X276609Y86179D01*
G01X277233Y87004D02*
X276373Y86179D01*
G01X277281Y87277D02*
X276136Y86179D01*
G01X277328Y87551D02*
X275899Y86179D01*
G01X277376Y87824D02*
X275663Y86179D01*
G01X277425Y88097D02*
X275425Y86179D01*
G01X277472Y88370D02*
X275188Y86179D01*
G01X277519Y88644D02*
X274951Y86179D01*
G01X277567Y88916D02*
X274715Y86179D01*
G01X277616Y89189D02*
X274479Y86179D01*
G01X277663Y89462D02*
X274241Y86179D01*
G01X277711Y89736D02*
X274004Y86179D01*
G01X277760Y90008D02*
X273766Y86179D01*
G01X277807Y90281D02*
X273530Y86179D01*
G01X277652Y90361D02*
X273293Y86179D01*
G01X273033Y86157D02*
X273056Y86179D01*
G01X277415Y90361D02*
X273056Y86179D01*
G01X293216Y82570D02*
X293264Y82843D01*
G01X293551Y84481D02*
X293599Y84755D01*
G01X293504Y84209D02*
X293551Y84481D01*
G01X293456Y83936D02*
X293504Y84209D01*
G01X293408Y83663D02*
X293456Y83936D01*
G01X293313Y83116D02*
X293360Y83389D01*
G01X293264Y82843D02*
X293313Y83116D01*
G01X293360Y83389D02*
X293408Y83663D01*
G01X281491Y88136D02*
X281555Y87969D01*
G01X281428Y88303D02*
X281491Y88136D01*
G01X281679Y87635D02*
X281743Y87468D01*
G01X281555Y87969D02*
X281617Y87802D01*
G01X281743Y87468D02*
X281805Y87302D01*
G01X281366Y88470D02*
X281428Y88303D01*
G01X281617Y87802D02*
X281679Y87635D01*
G01X292978Y81204D02*
X293025Y81478D01*
G01X293073Y81751D02*
X293120Y82024D01*
G01D02*
X293169Y82296D01*
G01X281302Y88637D02*
X281366Y88470D01*
G01X281178Y88970D02*
X281240Y88804D01*
G01X293169Y82296D02*
X293216Y82570D01*
G01X293025Y81478D02*
X293073Y81751D01*
G01X281240Y88804D02*
X281302Y88637D01*
G01X282245Y86133D02*
X282309Y85966D01*
G01X282183Y86299D02*
X282245Y86133D01*
G01X281868Y87134D02*
X281932Y86967D01*
G01D02*
X281994Y86801D01*
G01X281805Y87302D02*
X281868Y87134D01*
G01X282120Y86467D02*
X282183Y86299D01*
G01X282056Y86634D02*
X282120Y86467D01*
G01X281994Y86801D02*
X282056Y86634D01*
G01X289177Y84830D02*
X289130Y84557D01*
G01D02*
X289081Y84283D01*
G01X272841Y85064D02*
X272889Y85336D01*
G01D02*
X272936Y85610D01*
G01D02*
X272985Y85883D01*
G01X272793Y84790D02*
X272841Y85064D01*
G01X277090Y86185D02*
X277137Y86459D01*
G01X277519Y88644D02*
X277567Y88916D01*
G01D02*
X277616Y89189D01*
G01X275188Y86179D02*
X275425D01*
G01X274951D02*
X275188D01*
G01X277425Y88097D02*
X277472Y88370D01*
G01X274715Y86179D02*
X274479D01*
G01X277376Y87824D02*
X277425Y88097D01*
G01X274715Y86179D02*
X274951D01*
G01X275425D02*
X275663D01*
G01X277472Y88370D02*
X277519Y88644D01*
G01X277711Y89736D02*
X277760Y90008D01*
G01X276136Y86179D02*
X276373D01*
G01X275663D02*
X275899D01*
G01D02*
X276136D01*
G01X274479D02*
X274241D01*
G01X277663Y89462D02*
X277711Y89736D01*
G01X277137Y86459D02*
X277184Y86731D01*
G01X277328Y87551D02*
X277376Y87824D01*
G01X274004Y86179D02*
X273766D01*
G01X277233Y87004D02*
X277281Y87277D01*
G01D02*
X277328Y87551D01*
G01X274241Y86179D02*
X274004D01*
G01X273766D02*
X273530D01*
G01X277760Y90008D02*
X277807Y90281D01*
G01X273293Y86179D02*
X273056D01*
G01X277184Y86731D02*
X277233Y87004D01*
G01X273530Y86179D02*
X273293D01*
G01X277616Y89189D02*
X277663Y89462D01*
G01X275047Y90361D02*
X274811D01*
G01X275284D02*
X275047D01*
G01X275758D02*
X275520D01*
G01D02*
X275284D01*
G01X272553Y83423D02*
X272600Y83697D01*
G01X276231Y90361D02*
X275995D01*
G01D02*
X275758D01*
G01X272696Y84244D02*
X272649Y83971D01*
G01D02*
X272600Y83697D01*
G01X274336Y90361D02*
X274100D01*
G01X273893Y91071D02*
X273940Y91344D01*
G01D02*
X273989Y91618D01*
G01X276468Y90361D02*
X276231D01*
G01X274811D02*
X274573D01*
G01D02*
X274336D01*
G01X273796Y90525D02*
X273845Y90798D01*
G01D02*
X273893Y91071D01*
G01X274100Y90361D02*
X273863D01*
G01X272745Y84516D02*
X272793Y84790D01*
G01X277090Y86185D02*
X277088Y86179D01*
X277083D01*
G01X276845D02*
X277083D01*
G01X277807Y90281D02*
X277821Y90361D01*
X277652D01*
G01X272696Y84244D02*
X272745Y84516D01*
G01X276609Y86179D02*
X276845D01*
G01X277179Y90361D02*
X276943D01*
G01X272456Y82877D02*
X272505Y83151D01*
G01X276373Y86179D02*
X276609D01*
G01X276706Y90361D02*
X276468D01*
G01X276943D02*
X276706D01*
G01X277652D02*
X277415D01*
G01D02*
X277179D01*
G01X272505Y83151D02*
X272553Y83423D01*
G01X273796Y90525D02*
X273768Y90361D01*
X273863D01*
G01X272985Y85883D02*
X273033Y86157D01*
G01D02*
X273037Y86179D01*
X273056D01*
G01X274651Y96797D02*
X274196Y96589D01*
G01X274469Y94350D02*
X274517Y94624D01*
G01X274196Y96589D02*
X273743Y96380D01*
G01X273288Y96171D02*
X272832Y95962D01*
G01X273743Y96380D02*
X273288Y96171D01*
G01X274902Y96810D02*
X274921Y96922D01*
X274651Y96797D01*
G01X274565Y94898D02*
X274613Y95171D01*
G01D02*
X274662Y95443D01*
G01X274517Y94624D02*
X274565Y94898D01*
G01X274805Y96264D02*
X274853Y96536D01*
G01X274757Y95990D02*
X274805Y96264D01*
G01X274662Y95443D02*
X274709Y95717D01*
G01D02*
X274757Y95990D01*
G01X274853Y96536D02*
X274902Y96810D01*
G01X273989Y91618D02*
X274036Y91891D01*
G01X274373Y93805D02*
X274420Y94077D01*
G01X274182Y92711D02*
X274229Y92984D01*
G01X274036Y91891D02*
X274085Y92164D01*
G01X274325Y93531D02*
X274373Y93805D01*
G01X274229Y92984D02*
X274276Y93257D01*
G01X274420Y94077D02*
X274469Y94350D01*
G01X274085Y92164D02*
X274133Y92438D01*
G01X274276Y93257D02*
X274325Y93531D01*
G01X274133Y92438D02*
X274182Y92711D01*
G01X293569Y87225D02*
X287190Y81105D01*
G01X293522Y87407D02*
X286995Y81146D01*
G01X293454Y87570D02*
X286791Y81179D01*
G01X293387Y87732D02*
X286584Y81206D01*
G01X293321Y87895D02*
X286368Y81225D01*
G01X293254Y88059D02*
X286146Y81240D01*
G01X293187Y88222D02*
X289081Y84283D01*
G01X288909Y84119D02*
X285919Y81251D01*
G01X293109Y88375D02*
X289130Y84557D01*
G01X288750Y84194D02*
X285689Y81256D01*
G01X288591Y84268D02*
X285455Y81259D01*
G01X293009Y88505D02*
X289177Y84830D01*
G01X288424Y84335D02*
X285183Y81225D01*
G01X292907Y88635D02*
X289206Y85085D01*
G01X288245Y84392D02*
X284909Y81191D01*
G01X292805Y88766D02*
X289227Y85332D01*
G01X284638Y81157D02*
X288068Y84447D01*
G01X292705Y88895D02*
X289206Y85538D01*
G01X284365Y81123D02*
X287890Y84504D01*
G01X292603Y89025D02*
X289181Y85743D01*
G01X292502Y89156D02*
X289123Y85914D01*
G01X292375Y89261D02*
X289065Y86086D01*
G01X292243Y89361D02*
X288976Y86228D01*
G01X292111Y89461D02*
X288886Y86367D01*
G01X291978Y89561D02*
X288774Y86488D01*
G01X291845Y89662D02*
X288651Y86598D01*
G01X291714Y89761D02*
X288521Y86700D01*
G01X291575Y89856D02*
X288369Y86780D01*
G01X291412Y89928D02*
X288214Y86860D01*
G01X291250Y90000D02*
X288037Y86917D01*
G01X291088Y90071D02*
X287852Y86967D01*
G01X290927Y90143D02*
X287658Y87008D01*
G01X290764Y90215D02*
X287438Y87025D01*
G01X290603Y90287D02*
X287220Y87043D01*
G01X290425Y90345D02*
X286985Y87044D01*
G01X290235Y90388D02*
X286744Y87039D01*
G01X290044Y90432D02*
X286501Y87035D01*
G01X289851Y90476D02*
X286250Y87021D01*
G01X289661Y90520D02*
X285995Y87003D01*
G01X289470Y90564D02*
X285738Y86984D01*
G01X289279Y90608D02*
X285464Y86948D01*
G01X289062Y90627D02*
X285190Y86913D01*
G01X288841Y90642D02*
X284893Y86854D01*
G01X278921Y81352D02*
X281224Y83562D01*
G01X288621Y90657D02*
X284591Y86792D01*
G01X288399Y90673D02*
X284258Y86700D01*
G01X283908Y86591D02*
X288178Y90688D01*
G01X283533Y86459D02*
X287956Y90703D01*
G01X283117Y86287D02*
X287730Y90712D01*
G01X282668Y86084D02*
X287486Y90705D01*
G01X282309Y85966D02*
X287242Y90699D01*
G01X282245Y86133D02*
X286998Y90692D01*
G01X282183Y86299D02*
X286749Y90681D01*
G01X282120Y86467D02*
X286489Y90657D01*
G01X282056Y86634D02*
X286227Y90634D01*
G01X281994Y86801D02*
X285965Y90611D01*
G01X281932Y86967D02*
X285687Y90570D01*
G01X281868Y87134D02*
X285404Y90525D01*
G01X281805Y87302D02*
X285119Y90480D01*
G01X281743Y87468D02*
X284811Y90412D01*
G01X281679Y87635D02*
X284499Y90339D01*
G01X281617Y87802D02*
X284176Y90257D01*
G01X281555Y87969D02*
X283825Y90148D01*
G01X281491Y88136D02*
X283474Y90038D01*
G01X281428Y88303D02*
X283080Y89887D01*
G01X281366Y88470D02*
X282680Y89730D01*
G01X281302Y88637D02*
X282234Y89531D01*
G01X281240Y88804D02*
X281772Y89314D01*
G01X281178Y88970D02*
X281277Y89066D01*
G01X277090Y86185D02*
X277083Y86179D01*
G01X277137Y86459D02*
X276845Y86179D01*
G01X277184Y86731D02*
X276609Y86179D01*
G01X277233Y87004D02*
X276373Y86179D01*
G01X277281Y87277D02*
X276136Y86179D01*
G01X277328Y87551D02*
X275899Y86179D01*
G01X277376Y87824D02*
X275663Y86179D01*
G01X277425Y88097D02*
X275425Y86179D01*
G01X277472Y88370D02*
X275188Y86179D01*
G01X277519Y88644D02*
X274951Y86179D01*
G01X277567Y88916D02*
X274715Y86179D01*
G01X277616Y89189D02*
X274479Y86179D01*
G01X277663Y89462D02*
X274241Y86179D01*
G01X277711Y89736D02*
X274004Y86179D01*
G01X277760Y90008D02*
X273766Y86179D01*
G01X277807Y90281D02*
X273530Y86179D01*
G01X277652Y90361D02*
X273293Y86179D01*
G01X273033Y86157D02*
X273056Y86179D01*
G01X277415Y90361D02*
X273056Y86179D01*
G01X293216Y82570D02*
X293264Y82843D01*
G01X293551Y84481D02*
X293599Y84755D01*
G01X293504Y84209D02*
X293551Y84481D01*
G01X293456Y83936D02*
X293504Y84209D01*
G01X293408Y83663D02*
X293456Y83936D01*
G01X293313Y83116D02*
X293360Y83389D01*
G01X293264Y82843D02*
X293313Y83116D01*
G01X293360Y83389D02*
X293408Y83663D01*
G01X281491Y88136D02*
X281555Y87969D01*
G01X281428Y88303D02*
X281491Y88136D01*
G01X281679Y87635D02*
X281743Y87468D01*
G01X281555Y87969D02*
X281617Y87802D01*
G01X281743Y87468D02*
X281805Y87302D01*
G01X281366Y88470D02*
X281428Y88303D01*
G01X281617Y87802D02*
X281679Y87635D01*
G01X292978Y81204D02*
X293025Y81478D01*
G01X293073Y81751D02*
X293120Y82024D01*
G01D02*
X293169Y82296D01*
G01X281302Y88637D02*
X281366Y88470D01*
G01X281178Y88970D02*
X281240Y88804D01*
G01X293169Y82296D02*
X293216Y82570D01*
G01X293025Y81478D02*
X293073Y81751D01*
G01X281240Y88804D02*
X281302Y88637D01*
G01X282245Y86133D02*
X282309Y85966D01*
G01X282183Y86299D02*
X282245Y86133D01*
G01X281868Y87134D02*
X281932Y86967D01*
G01D02*
X281994Y86801D01*
G01X281805Y87302D02*
X281868Y87134D01*
G01X282120Y86467D02*
X282183Y86299D01*
G01X282056Y86634D02*
X282120Y86467D01*
G01X281994Y86801D02*
X282056Y86634D01*
G01X289177Y84830D02*
X289130Y84557D01*
G01D02*
X289081Y84283D01*
G01X272841Y85064D02*
X272889Y85336D01*
G01D02*
X272936Y85610D01*
G01D02*
X272985Y85883D01*
G01X272793Y84790D02*
X272841Y85064D01*
G01X277090Y86185D02*
X277137Y86459D01*
G01X277519Y88644D02*
X277567Y88916D01*
G01D02*
X277616Y89189D01*
G01X275188Y86179D02*
X275425D01*
G01X274951D02*
X275188D01*
G01X277425Y88097D02*
X277472Y88370D01*
G01X274715Y86179D02*
X274479D01*
G01X277376Y87824D02*
X277425Y88097D01*
G01X274715Y86179D02*
X274951D01*
G01X275425D02*
X275663D01*
G01X277472Y88370D02*
X277519Y88644D01*
G01X277711Y89736D02*
X277760Y90008D01*
G01X276136Y86179D02*
X276373D01*
G01X275663D02*
X275899D01*
G01D02*
X276136D01*
G01X274479D02*
X274241D01*
G01X277663Y89462D02*
X277711Y89736D01*
G01X277137Y86459D02*
X277184Y86731D01*
G01X277328Y87551D02*
X277376Y87824D01*
G01X274004Y86179D02*
X273766D01*
G01X277233Y87004D02*
X277281Y87277D01*
G01D02*
X277328Y87551D01*
G01X274241Y86179D02*
X274004D01*
G01X273766D02*
X273530D01*
G01X277760Y90008D02*
X277807Y90281D01*
G01X273293Y86179D02*
X273056D01*
G01X277184Y86731D02*
X277233Y87004D01*
G01X273530Y86179D02*
X273293D01*
G01X277616Y89189D02*
X277663Y89462D01*
G01X275047Y90361D02*
X274811D01*
G01X275284D02*
X275047D01*
G01X275758D02*
X275520D01*
G01D02*
X275284D01*
G01X272553Y83423D02*
X272600Y83697D01*
G01X276231Y90361D02*
X275995D01*
G01D02*
X275758D01*
G01X272696Y84244D02*
X272649Y83971D01*
G01D02*
X272600Y83697D01*
G01X274336Y90361D02*
X274100D01*
G01X273893Y91071D02*
X273940Y91344D01*
G01D02*
X273989Y91618D01*
G01X276468Y90361D02*
X276231D01*
G01X274811D02*
X274573D01*
G01D02*
X274336D01*
G01X273796Y90525D02*
X273845Y90798D01*
G01D02*
X273893Y91071D01*
G01X274100Y90361D02*
X273863D01*
G01X272745Y84516D02*
X272793Y84790D01*
G01X277090Y86185D02*
X277088Y86179D01*
X277083D01*
G01X276845D02*
X277083D01*
G01X277807Y90281D02*
X277821Y90361D01*
X277652D01*
G01X272696Y84244D02*
X272745Y84516D01*
G01X276609Y86179D02*
X276845D01*
G01X277179Y90361D02*
X276943D01*
G01X272456Y82877D02*
X272505Y83151D01*
G01X276373Y86179D02*
X276609D01*
G01X276706Y90361D02*
X276468D01*
G01X276943D02*
X276706D01*
G01X277652D02*
X277415D01*
G01D02*
X277179D01*
G01X272505Y83151D02*
X272553Y83423D01*
G01X273796Y90525D02*
X273768Y90361D01*
X273863D01*
G01X272985Y85883D02*
X273033Y86157D01*
G01D02*
X273037Y86179D01*
X273056D01*
G01X274651Y96797D02*
X274196Y96589D01*
G01X274469Y94350D02*
X274517Y94624D01*
G01X274196Y96589D02*
X273743Y96380D01*
G01X273288Y96171D02*
X272832Y95962D01*
G01X273743Y96380D02*
X273288Y96171D01*
G01X274902Y96810D02*
X274921Y96922D01*
X274651Y96797D01*
G01X274565Y94898D02*
X274613Y95171D01*
G01D02*
X274662Y95443D01*
G01X274517Y94624D02*
X274565Y94898D01*
G01X274805Y96264D02*
X274853Y96536D01*
G01X274757Y95990D02*
X274805Y96264D01*
G01X274662Y95443D02*
X274709Y95717D01*
G01D02*
X274757Y95990D01*
G01X274853Y96536D02*
X274902Y96810D01*
G01X273989Y91618D02*
X274036Y91891D01*
G01X274373Y93805D02*
X274420Y94077D01*
G01X274182Y92711D02*
X274229Y92984D01*
G01X274036Y91891D02*
X274085Y92164D01*
G01X274325Y93531D02*
X274373Y93805D01*
G01X274229Y92984D02*
X274276Y93257D01*
G01X274420Y94077D02*
X274469Y94350D01*
G01X274085Y92164D02*
X274133Y92438D01*
G01X274276Y93257D02*
X274325Y93531D01*
G01X274133Y92438D02*
X274182Y92711D01*
G01X309600Y-829672D02*
Y-824672D01*
X310866D01*
X311373Y-824922D01*
X311753Y-825255D01*
X312070Y-825755D01*
X312323Y-826339D01*
X312386Y-827172D01*
X312323Y-828005D01*
X312070Y-828589D01*
X311753Y-829089D01*
X311373Y-829422D01*
X310866Y-829672D01*
X309600D01*
G01X314510D02*
X316093Y-824672D01*
X317676Y-829672D01*
G01X317106Y-827922D02*
X315080D01*
G01X321193Y-824672D02*
Y-829672D01*
G01X319736Y-824672D02*
X322650D01*
G01X327560Y-829672D02*
X325026D01*
Y-824672D01*
X327560D01*
G01X326546Y-827089D02*
X325026D01*
G01X331393Y-829839D02*
X331266Y-829755D01*
Y-829589D01*
X331393Y-829505D01*
X331520Y-829589D01*
Y-829755D01*
X331393Y-829839D01*
G01Y-827589D02*
X331266Y-827505D01*
Y-827339D01*
X331393Y-827255D01*
X331520Y-827339D01*
Y-827505D01*
X331393Y-827589D01*
G01X304093Y-769672D02*
Y-844672D01*
G01X302093Y-769672D02*
Y-844672D01*
G01X304093Y-819672D02*
X504093D01*
G01X309726Y-804672D02*
Y-799672D01*
X311246D01*
X311753Y-799922D01*
X312133Y-800505D01*
X312260Y-801172D01*
X312133Y-801839D01*
X311816Y-802339D01*
X311246Y-802589D01*
X309726D01*
G01X314953Y-804839D02*
X317233Y-799672D01*
G01X319736Y-804672D02*
Y-799672D01*
X322650Y-804672D01*
Y-799672D01*
G01X326293Y-804839D02*
X326166Y-804755D01*
Y-804589D01*
X326293Y-804505D01*
X326420Y-804589D01*
Y-804755D01*
X326293Y-804839D01*
G01Y-802589D02*
X326166Y-802505D01*
Y-802339D01*
X326293Y-802255D01*
X326420Y-802339D01*
Y-802505D01*
X326293Y-802589D01*
G01X304093Y-794672D02*
X504093D01*
G01X309726Y-779672D02*
Y-774672D01*
X311246D01*
X311753Y-774922D01*
X312133Y-775505D01*
X312260Y-776172D01*
X312133Y-776839D01*
X311816Y-777339D01*
X311246Y-777589D01*
X309726D01*
G01X314826Y-779672D02*
Y-774672D01*
X316410D01*
X316916Y-774922D01*
X317233Y-775255D01*
X317360Y-775922D01*
X317233Y-776589D01*
X316853Y-777005D01*
X316410Y-777255D01*
X314826D01*
G01X316410D02*
X317360Y-779672D01*
G01X321193D02*
X320686Y-779589D01*
X320243Y-779255D01*
X319863Y-778755D01*
X319610Y-778172D01*
X319483Y-777505D01*
Y-776839D01*
X319610Y-776172D01*
X319863Y-775589D01*
X320243Y-775089D01*
X320686Y-774755D01*
X321193Y-774672D01*
X321700Y-774755D01*
X322143Y-775089D01*
X322523Y-775589D01*
X322776Y-776172D01*
X322903Y-776839D01*
Y-777505D01*
X322776Y-778172D01*
X322523Y-778755D01*
X322143Y-779255D01*
X321700Y-779589D01*
X321193Y-779672D01*
G01X325026Y-778672D02*
X325343Y-779172D01*
X325723Y-779505D01*
X326166Y-779672D01*
X326673Y-779505D01*
X327053Y-779172D01*
X327433Y-778672D01*
X327560Y-778005D01*
Y-774672D01*
G01X332660Y-779672D02*
X330126D01*
Y-774672D01*
X332660D01*
G01X331646Y-777089D02*
X330126D01*
G01X337886Y-775089D02*
X337506Y-774839D01*
X337063Y-774672D01*
X336556D01*
X335986Y-774922D01*
X335543Y-775339D01*
X335226Y-775839D01*
X334973Y-776672D01*
X334910Y-777422D01*
X335036Y-778172D01*
X335226Y-778672D01*
X335606Y-779172D01*
X336050Y-779505D01*
X336493Y-779672D01*
X336936D01*
X337380Y-779505D01*
X337760Y-779255D01*
X338076Y-778922D01*
G01X341593Y-774672D02*
Y-779672D01*
G01X340136Y-774672D02*
X343050D01*
G01X346693Y-779839D02*
X346566Y-779755D01*
Y-779589D01*
X346693Y-779505D01*
X346820Y-779589D01*
Y-779755D01*
X346693Y-779839D01*
G01Y-777589D02*
X346566Y-777505D01*
Y-777339D01*
X346693Y-777255D01*
X346820Y-777339D01*
Y-777505D01*
X346693Y-777589D01*
G01X351299Y281339D02*
G02Y273071I0J-4134D01*
G02Y281339I0J4134D01*
G01X336299D02*
G02Y273071I0J-4134D01*
G02Y281339I0J4134D01*
G01X351299Y273071D02*
G03Y281339I0J4134D01*
G03Y273071I0J-4134D01*
G01X336299D02*
G03Y281339I0J4134D01*
G03Y273071I0J-4134D01*
G01X351299Y480354D02*
G02Y474055I0J-3149D01*
G02Y480354I0J3149D01*
G01Y474055D02*
G03Y480354I0J3149D01*
G03Y474055I0J-3149D01*
G01X381299Y480354D02*
G02Y474055I0J-3149D01*
G02Y480354I0J3149D01*
G01Y474055D02*
G03Y480354I0J3149D01*
G03Y474055I0J-3149D01*
G01X419093Y-819672D02*
Y-844672D01*
G01X425716Y57073D02*
X500000Y53150D01*
X511811D01*
G02Y41339I0J-5905D01*
G01X500000D01*
X425716Y37415D01*
G02Y57073I-519J9829D01*
G01D02*
G03Y37415I-519J-9829D01*
G01X500000Y41339D01*
X511811D01*
G03Y53150I0J5906D01*
G01X500000D01*
X425716Y57073D01*
G01X411299Y281339D02*
G02Y273071I0J-4134D01*
G02Y281339I0J4134D01*
G01Y273071D02*
G03Y281339I0J4134D01*
G03Y273071I0J-4134D01*
G01Y480354D02*
G02Y474055I0J-3149D01*
G02Y480354I0J3149D01*
G01Y474055D02*
G03Y480354I0J3149D01*
G03Y474055I0J-3149D01*
G01X421726Y-822172D02*
Y-827172D01*
X424260D01*
G01X427333Y-822172D02*
X428853D01*
G01X428093D02*
Y-827172D01*
G01X427333D02*
X428853D01*
G01X433700Y-824505D02*
X433953Y-824255D01*
X434143Y-823839D01*
X434270Y-823255D01*
X434143Y-822755D01*
X433890Y-822422D01*
X433446Y-822172D01*
X431736D01*
Y-827172D01*
X433826D01*
X434270Y-826839D01*
X434523Y-826339D01*
X434650Y-825755D01*
X434523Y-825172D01*
X434143Y-824672D01*
X433700Y-824505D01*
X431736D01*
G01X438293Y-827339D02*
X438166Y-827255D01*
Y-827089D01*
X438293Y-827005D01*
X438420Y-827089D01*
Y-827255D01*
X438293Y-827339D01*
G01Y-825089D02*
X438166Y-825005D01*
Y-824839D01*
X438293Y-824755D01*
X438420Y-824839D01*
Y-825005D01*
X438293Y-825089D01*
G01X426299Y281339D02*
G02Y273071I0J-4134D01*
G02Y281339I0J4134D01*
G01Y273071D02*
G03Y281339I0J4134D01*
G03Y273071I0J-4134D01*
G01X470106Y-847839D02*
X470213Y-847714D01*
X470293Y-847505D01*
X470346Y-847214D01*
X470293Y-846964D01*
X470186Y-846797D01*
X470000Y-846672D01*
X469280D01*
Y-849172D01*
X470160D01*
X470346Y-849005D01*
X470453Y-848755D01*
X470506Y-848464D01*
X470453Y-848172D01*
X470293Y-847922D01*
X470106Y-847839D01*
X469280D01*
G01X472573Y-849172D02*
Y-847505D01*
G01Y-847797D02*
X472466Y-847630D01*
X472306Y-847547D01*
X472120Y-847505D01*
X471933Y-847589D01*
X471773Y-847755D01*
X471666Y-848005D01*
X471613Y-848339D01*
X471666Y-848672D01*
X471773Y-848922D01*
X471933Y-849089D01*
X472120Y-849172D01*
X472306Y-849130D01*
X472466Y-849005D01*
X472573Y-848839D01*
G01X473893Y-848880D02*
X474026Y-849047D01*
X474213Y-849172D01*
X474373D01*
X474533Y-849089D01*
X474640Y-848964D01*
X474693Y-848797D01*
X474666Y-848547D01*
X474560Y-848422D01*
X474080Y-848172D01*
X473973Y-847880D01*
X474026Y-847672D01*
X474133Y-847547D01*
X474293Y-847505D01*
X474453Y-847547D01*
X474613Y-847672D01*
G01X476093Y-848047D02*
X476946D01*
X476866Y-847755D01*
X476733Y-847589D01*
X476546Y-847505D01*
X476360Y-847547D01*
X476200Y-847672D01*
X476093Y-847964D01*
X476040Y-848214D01*
Y-848464D01*
X476093Y-848714D01*
X476226Y-848964D01*
X476386Y-849130D01*
X476573Y-849172D01*
X476760Y-849089D01*
X476946Y-848839D01*
G01X478213Y-849172D02*
Y-846672D01*
G01Y-847922D02*
X478346Y-847672D01*
X478506Y-847547D01*
X478666Y-847505D01*
X478906Y-847589D01*
X479066Y-847755D01*
X479173Y-848047D01*
Y-848380D01*
X479120Y-848714D01*
X479013Y-848964D01*
X478826Y-849130D01*
X478666Y-849172D01*
X478506Y-849130D01*
X478346Y-849005D01*
X478213Y-848797D01*
G01X480893Y-849172D02*
X480733Y-849130D01*
X480573Y-848964D01*
X480466Y-848672D01*
X480413Y-848339D01*
X480466Y-848005D01*
X480573Y-847714D01*
X480733Y-847547D01*
X480893Y-847505D01*
X481053Y-847547D01*
X481213Y-847714D01*
X481320Y-848005D01*
X481346Y-848339D01*
X481320Y-848672D01*
X481213Y-848964D01*
X481053Y-849130D01*
X480893Y-849172D01*
G01X483573D02*
Y-847505D01*
G01Y-847797D02*
X483466Y-847630D01*
X483306Y-847547D01*
X483120Y-847505D01*
X482933Y-847589D01*
X482773Y-847755D01*
X482666Y-848005D01*
X482613Y-848339D01*
X482666Y-848672D01*
X482773Y-848922D01*
X482933Y-849089D01*
X483120Y-849172D01*
X483306Y-849130D01*
X483466Y-849005D01*
X483573Y-848839D01*
G01X484920Y-849172D02*
Y-847505D01*
G01Y-847839D02*
X485053Y-847672D01*
X485186Y-847547D01*
X485373Y-847505D01*
X485506Y-847547D01*
X485666Y-847672D01*
G01X487973Y-846672D02*
Y-849172D01*
G01Y-848797D02*
X487866Y-849005D01*
X487706Y-849130D01*
X487520Y-849172D01*
X487306Y-849089D01*
X487146Y-848880D01*
X487040Y-848630D01*
X487013Y-848339D01*
X487040Y-848047D01*
X487146Y-847797D01*
X487306Y-847589D01*
X487520Y-847505D01*
X487706Y-847547D01*
X487840Y-847630D01*
X487973Y-847797D01*
G01X491360Y-849172D02*
Y-846672D01*
X492026D01*
X492240Y-846797D01*
X492373Y-846964D01*
X492426Y-847297D01*
X492373Y-847630D01*
X492213Y-847839D01*
X492026Y-847964D01*
X491360D01*
G01X492026D02*
X492426Y-849172D01*
G01X493693Y-848047D02*
X494546D01*
X494466Y-847755D01*
X494333Y-847589D01*
X494146Y-847505D01*
X493960Y-847547D01*
X493800Y-847672D01*
X493693Y-847964D01*
X493640Y-848214D01*
Y-848464D01*
X493693Y-848714D01*
X493826Y-848964D01*
X493986Y-849130D01*
X494173Y-849172D01*
X494360Y-849089D01*
X494546Y-848839D01*
G01X495813Y-847505D02*
X496293Y-849172D01*
X496773Y-847505D01*
G01X498493Y-849255D02*
X498440Y-849214D01*
Y-849130D01*
X498493Y-849089D01*
X498546Y-849130D01*
Y-849214D01*
X498493Y-849255D01*
G01X500693Y-849172D02*
X500880Y-849130D01*
X501093Y-849005D01*
X501226Y-848797D01*
X501280Y-848505D01*
X501226Y-848214D01*
X501066Y-847964D01*
X500826Y-847839D01*
X500560D01*
X500400Y-847755D01*
X500266Y-847547D01*
X500213Y-847255D01*
X500293Y-846964D01*
X500480Y-846755D01*
X500693Y-846672D01*
X500906Y-846755D01*
X501093Y-846964D01*
X501173Y-847255D01*
X501120Y-847547D01*
X500986Y-847755D01*
X500826Y-847839D01*
X500560D01*
X500320Y-847964D01*
X500160Y-848214D01*
X500106Y-848505D01*
X500160Y-848797D01*
X500293Y-849005D01*
X500506Y-849130D01*
X500693Y-849172D01*
G01X503106Y-847839D02*
X503213Y-847714D01*
X503293Y-847505D01*
X503346Y-847214D01*
X503293Y-846964D01*
X503186Y-846797D01*
X503000Y-846672D01*
X502280D01*
Y-849172D01*
X503160D01*
X503346Y-849005D01*
X503453Y-848755D01*
X503506Y-848464D01*
X503453Y-848172D01*
X503293Y-847922D01*
X503106Y-847839D01*
X502280D01*
G01X465993Y-822172D02*
Y-827172D01*
G01X464536Y-822172D02*
X467450D01*
G01X471093Y-827172D02*
X470713Y-827089D01*
X470333Y-826755D01*
X470080Y-826172D01*
X469953Y-825505D01*
X470080Y-824839D01*
X470333Y-824255D01*
X470713Y-823922D01*
X471093Y-823839D01*
X471473Y-823922D01*
X471853Y-824255D01*
X472106Y-824839D01*
X472170Y-825505D01*
X472106Y-826172D01*
X471853Y-826755D01*
X471473Y-827089D01*
X471093Y-827172D01*
G01X476193D02*
X475813Y-827089D01*
X475433Y-826755D01*
X475180Y-826172D01*
X475053Y-825505D01*
X475180Y-824839D01*
X475433Y-824255D01*
X475813Y-823922D01*
X476193Y-823839D01*
X476573Y-823922D01*
X476953Y-824255D01*
X477206Y-824839D01*
X477270Y-825505D01*
X477206Y-826172D01*
X476953Y-826755D01*
X476573Y-827089D01*
X476193Y-827172D01*
G01X481293D02*
Y-822172D01*
G01X486393Y-827339D02*
X486266Y-827255D01*
Y-827089D01*
X486393Y-827005D01*
X486520Y-827089D01*
Y-827255D01*
X486393Y-827339D01*
G01Y-825089D02*
X486266Y-825005D01*
Y-824839D01*
X486393Y-824755D01*
X486520Y-824839D01*
Y-825005D01*
X486393Y-825089D01*
G01X462093Y-819672D02*
Y-844672D01*
G01Y-794672D02*
Y-819672D01*
G01X464726Y-802172D02*
Y-797172D01*
X466310D01*
X466816Y-797422D01*
X467133Y-797755D01*
X467260Y-798422D01*
X467133Y-799089D01*
X466753Y-799505D01*
X466310Y-799755D01*
X464726D01*
G01X466310D02*
X467260Y-802172D01*
G01X472360D02*
X469826D01*
Y-797172D01*
X472360D01*
G01X471346Y-799589D02*
X469826D01*
G01X474610Y-797172D02*
X476193Y-802172D01*
X477776Y-797172D01*
G01X481293Y-802339D02*
X481166Y-802255D01*
Y-802089D01*
X481293Y-802005D01*
X481420Y-802089D01*
Y-802255D01*
X481293Y-802339D01*
G01Y-800089D02*
X481166Y-800005D01*
Y-799839D01*
X481293Y-799755D01*
X481420Y-799839D01*
Y-800005D01*
X481293Y-800089D01*
G01X508780Y281339D02*
G02Y273071I0J-4134D01*
G02Y281339I0J4134D01*
G01X493780D02*
G02Y273071I0J-4134D01*
G02Y281339I0J4134D01*
G01X508780Y273071D02*
G03Y281339I0J4134D01*
G03Y273071I0J-4134D01*
G01X493780D02*
G03Y281339I0J4134D01*
G03Y273071I0J-4134D01*
G01X508780Y480354D02*
G02Y474055I0J-3149D01*
G02Y480354I0J3149D01*
G01Y474055D02*
G03Y480354I0J3149D01*
G03Y474055I0J-3149D01*
G01X538780Y480354D02*
G02Y474055I0J-3149D01*
G02Y480354I0J3149D01*
G01Y474055D02*
G03Y480354I0J3149D01*
G03Y474055I0J-3149D01*
G01X568780Y281339D02*
G02Y273071I0J-4134D01*
G02Y281339I0J4134D01*
G01Y273071D02*
G03Y281339I0J4134D01*
G03Y273071I0J-4134D01*
G01Y480354D02*
G02Y474055I0J-3149D01*
G02Y480354I0J3149D01*
G01Y474055D02*
G03Y480354I0J3149D01*
G03Y474055I0J-3149D01*
G01X583780Y281339D02*
G02Y273071I0J-4134D01*
G02Y281339I0J4134D01*
G01Y273071D02*
G03Y281339I0J4134D01*
G03Y273071I0J-4134D01*
G01X651260Y281339D02*
G02Y273071I0J-4134D01*
G02Y281339I0J4134D01*
G01Y273071D02*
G03Y281339I0J4134D01*
G03Y273071I0J-4134D01*
G01X666260Y281339D02*
G02Y273071I0J-4134D01*
G02Y281339I0J4134D01*
G01Y273071D02*
G03Y281339I0J4134D01*
G03Y273071I0J-4134D01*
G01Y480354D02*
G02Y474055I0J-3149D01*
G02Y480354I0J3149D01*
G01Y474055D02*
G03Y480354I0J3149D01*
G03Y474055I0J-3149D01*
G01X696260Y480354D02*
G02Y474055I0J-3149D01*
G02Y480354I0J3149D01*
G01Y474055D02*
G03Y480354I0J3149D01*
G03Y474055I0J-3149D01*
G01X741260Y281339D02*
G02Y273071I0J-4134D01*
G02Y281339I0J4134D01*
G01X726260D02*
G02Y273071I0J-4134D01*
G02Y281339I0J4134D01*
G01X741260Y273071D02*
G03Y281339I0J4134D01*
G03Y273071I0J-4134D01*
G01X726260D02*
G03Y281339I0J4134D01*
G03Y273071I0J-4134D01*
G01Y480354D02*
G02Y474055I0J-3149D01*
G02Y480354I0J3149D01*
G01Y474055D02*
G03Y480354I0J3149D01*
G03Y474055I0J-3149D01*
G01X905512Y41339D02*
X893701D01*
X819417Y37415D01*
G02Y57073I-519J9829D01*
G01X893701Y53150D01*
X905512D01*
G02Y41339I0J-5905D01*
G01Y53150D02*
G02Y41339I0J-5905D01*
G01X893701D01*
X819417Y37415D01*
G02Y57073I-519J9829D01*
G01X893701Y53150D01*
X905512D01*
G01X902488Y237782D02*
X976772Y233858D01*
X988583D01*
G02Y222047I0J-5905D01*
G01X976772D01*
X902488Y218124D01*
G02Y237782I-519J9829D01*
G01D02*
G03Y218124I-519J-9829D01*
G01X976772Y222047D01*
X988583D01*
G03Y233858I0J5906D01*
G01X976772D01*
X902488Y237782D01*
G01X944417Y552309D02*
X1018701Y548386D01*
X1030512D01*
G02Y536575I0J-5905D01*
G01X1018701D01*
X944417Y532651D01*
G02Y552309I-519J9829D01*
G01D02*
G03Y532651I-519J-9829D01*
G01X1018701Y536575D01*
X1030512D01*
G03Y548386I0J5905D01*
G01X1018701D01*
X944417Y552309D01*
G01X1226024Y182736D02*
G02Y166122I0J-8307D01*
G02Y182736I0J8307D01*
G01Y166122D02*
G03Y182736I0J8307D01*
G03Y166122I0J-8307D01*
G01Y407736D02*
G02Y391122I0J-8307D01*
G02Y407736I0J8307D01*
G01Y391122D02*
G03Y407736I0J8307D01*
G03Y391122I0J-8307D01*
G01X1227559Y57480D02*
G02X1252756I12599J0D01*
G02X1227559I-12598J0D01*
G01X1252756D02*
G03X1227559I-12598J0D01*
G03X1252756I12599J0D01*
G01X1227559Y521260D02*
G02X1252756I12599J0D01*
G02X1227559I-12598J0D01*
G01X1252756D02*
G03X1227559I-12598J0D01*
G03X1252756I12599J0D01*
G01X-297025Y-1013390D02*
Y1828909D01*
X3691357D01*
Y-1013390D01*
X-297025D01*
G01X-23385Y382480D02*
X56142D01*
Y199409D01*
X-23385D01*
Y382480D01*
G01X124134Y120689D02*
Y78759D01*
X-1063D01*
Y120689D01*
X124134D01*
G01Y503170D02*
Y461240D01*
X-1063D01*
Y503170D01*
X124134D01*
G01X51117Y653000D02*
Y649900D01*
X50197D01*
X49890Y650055D01*
X49660Y650417D01*
X49583Y650830D01*
X49660Y651243D01*
X49852Y651553D01*
X50197Y651708D01*
X51117D01*
G01X47940Y653103D02*
X46560Y649900D01*
G01X45032Y653000D02*
Y649900D01*
X43268Y653000D01*
Y649900D01*
G01X41050Y653103D02*
X41127Y653052D01*
Y652948D01*
X41050Y652897D01*
X40973Y652948D01*
Y653052D01*
X41050Y653103D01*
G01Y651708D02*
X41127Y651657D01*
Y651553D01*
X41050Y651502D01*
X40973Y651553D01*
Y651657D01*
X41050Y651708D01*
G01X38793Y653000D02*
Y649900D01*
X38027D01*
X37720Y650055D01*
X37490Y650262D01*
X37298Y650572D01*
X37145Y650933D01*
X37107Y651450D01*
X37145Y651967D01*
X37298Y652328D01*
X37490Y652638D01*
X37720Y652845D01*
X38027Y653000D01*
X38793D01*
G01X35808D02*
X34850Y649900D01*
X33892Y653000D01*
G01X34237Y651915D02*
X35463D01*
G01X31750Y649900D02*
X32057Y650003D01*
X32287Y650262D01*
X32440Y650572D01*
X32555Y650985D01*
X32593Y651450D01*
X32555Y651915D01*
X32440Y652328D01*
X32287Y652638D01*
X32057Y652897D01*
X31750Y653000D01*
X31443Y652897D01*
X31213Y652638D01*
X31060Y652328D01*
X30945Y651915D01*
X30907Y651450D01*
X30945Y650985D01*
X31060Y650572D01*
X31213Y650262D01*
X31443Y650003D01*
X31750Y649900D01*
G01X29378Y653000D02*
Y649900D01*
X27922D01*
G01X28458Y651398D02*
X29378D01*
G01X25550Y649900D02*
X25857Y650003D01*
X26087Y650262D01*
X26240Y650572D01*
X26355Y650985D01*
X26393Y651450D01*
X26355Y651915D01*
X26240Y652328D01*
X26087Y652638D01*
X25857Y652897D01*
X25550Y653000D01*
X25243Y652897D01*
X25013Y652638D01*
X24860Y652328D01*
X24745Y651915D01*
X24707Y651450D01*
X24745Y650985D01*
X24860Y650572D01*
X25013Y650262D01*
X25243Y650003D01*
X25550Y649900D01*
G01X22450D02*
Y653000D01*
G01X23332Y649900D02*
X21568D01*
G01X20117Y653000D02*
Y649900D01*
X19197D01*
X18890Y650055D01*
X18660Y650417D01*
X18583Y650830D01*
X18660Y651243D01*
X18852Y651553D01*
X19197Y651708D01*
X20117D01*
G01X15943Y651347D02*
X15790Y651192D01*
X15675Y650933D01*
X15598Y650572D01*
X15675Y650262D01*
X15828Y650055D01*
X16097Y649900D01*
X17132D01*
Y653000D01*
X15867D01*
X15598Y652793D01*
X15445Y652483D01*
X15368Y652122D01*
X15445Y651760D01*
X15675Y651450D01*
X15943Y651347D01*
X17132D01*
G01X14108Y653000D02*
X13150Y649900D01*
X12192Y653000D01*
G01X12537Y651915D02*
X13763D01*
G01X10778Y653000D02*
Y649900D01*
X9322D01*
G01X9858Y651398D02*
X10778D01*
G01X6950Y649900D02*
X7257Y650003D01*
X7487Y650262D01*
X7640Y650572D01*
X7755Y650985D01*
X7793Y651450D01*
X7755Y651915D01*
X7640Y652328D01*
X7487Y652638D01*
X7257Y652897D01*
X6950Y653000D01*
X6643Y652897D01*
X6413Y652638D01*
X6260Y652328D01*
X6145Y651915D01*
X6107Y651450D01*
X6145Y650985D01*
X6260Y650572D01*
X6413Y650262D01*
X6643Y650003D01*
X6950Y649900D01*
G01X16913Y-817022D02*
X18480D01*
Y-818912D01*
X18010Y-819542D01*
X17461Y-819962D01*
X16678Y-820172D01*
X15895Y-819962D01*
X15346Y-819542D01*
X14876Y-818912D01*
X14563Y-818177D01*
X14406Y-817337D01*
Y-816602D01*
X14563Y-815972D01*
X14876Y-815237D01*
X15346Y-814607D01*
X15816Y-814187D01*
X16443Y-813872D01*
X16991D01*
X17618Y-814082D01*
X18088Y-814502D01*
G01X21020Y-813872D02*
Y-818387D01*
X21333Y-819332D01*
X21960Y-819962D01*
X22743Y-820172D01*
X23526Y-819962D01*
X24153Y-819332D01*
X24466Y-818387D01*
Y-813872D01*
G01X28103D02*
X29983D01*
G01X29043D02*
Y-820172D01*
G01X28103D02*
X29983D01*
G01X33698Y-819332D02*
X34325Y-819857D01*
X35030Y-820172D01*
X35656D01*
X36283Y-819857D01*
X36753Y-819332D01*
X36988Y-818597D01*
X36831Y-817862D01*
X36440Y-817232D01*
X35735Y-816812D01*
X34795Y-816602D01*
X34246Y-816182D01*
X34011Y-815447D01*
X34168Y-814712D01*
X34560Y-814187D01*
X35108Y-813872D01*
X35656D01*
X36205Y-814082D01*
X36675Y-814607D01*
G01X39998Y-820172D02*
Y-813872D01*
G01X43288D02*
Y-820172D01*
G01Y-817022D02*
X39998D01*
G01X45985Y-820172D02*
X47943Y-813872D01*
X49901Y-820172D01*
G01X49196Y-817967D02*
X46690D01*
G01X52441Y-820172D02*
Y-813872D01*
X56045Y-820172D01*
Y-813872D01*
G01X65120Y-820172D02*
Y-813872D01*
X66686D01*
X67313Y-814187D01*
X67783Y-814607D01*
X68175Y-815237D01*
X68488Y-815972D01*
X68566Y-817022D01*
X68488Y-818072D01*
X68175Y-818807D01*
X67783Y-819437D01*
X67313Y-819857D01*
X66686Y-820172D01*
X65120D01*
G01X72203Y-813872D02*
X74083D01*
G01X73143D02*
Y-820172D01*
G01X72203D02*
X74083D01*
G01X77798Y-819332D02*
X78425Y-819857D01*
X79130Y-820172D01*
X79756D01*
X80383Y-819857D01*
X80853Y-819332D01*
X81088Y-818597D01*
X80931Y-817862D01*
X80540Y-817232D01*
X79835Y-816812D01*
X78895Y-816602D01*
X78346Y-816182D01*
X78111Y-815447D01*
X78268Y-814712D01*
X78660Y-814187D01*
X79208Y-813872D01*
X79756D01*
X80305Y-814082D01*
X80775Y-814607D01*
G01X85743Y-813872D02*
Y-820172D01*
G01X83941Y-813872D02*
X87545D01*
G01X92043Y-820382D02*
X91886Y-820277D01*
Y-820067D01*
X92043Y-819962D01*
X92200Y-820067D01*
Y-820277D01*
X92043Y-820382D01*
G01X98186Y-821327D02*
X98500Y-819962D01*
G01X104643Y-813872D02*
Y-820172D01*
G01X102841Y-813872D02*
X106445D01*
G01X108985Y-820172D02*
X110943Y-813872D01*
X112901Y-820172D01*
G01X112196Y-817967D02*
X109690D01*
G01X117243Y-820172D02*
X116616Y-820067D01*
X116068Y-819647D01*
X115598Y-819017D01*
X115285Y-818282D01*
X115128Y-817442D01*
Y-816602D01*
X115285Y-815762D01*
X115598Y-815027D01*
X116068Y-814397D01*
X116616Y-813977D01*
X117243Y-813872D01*
X117870Y-813977D01*
X118418Y-814397D01*
X118888Y-815027D01*
X119201Y-815762D01*
X119358Y-816602D01*
Y-817442D01*
X119201Y-818282D01*
X118888Y-819017D01*
X118418Y-819647D01*
X117870Y-820067D01*
X117243Y-820172D01*
G01X123543D02*
Y-817337D01*
X121976Y-813872D01*
G01X125110D02*
X123543Y-817337D01*
G01X128120Y-813872D02*
Y-818387D01*
X128433Y-819332D01*
X129060Y-819962D01*
X129843Y-820172D01*
X130626Y-819962D01*
X131253Y-819332D01*
X131566Y-818387D01*
Y-813872D01*
G01X134185Y-820172D02*
X136143Y-813872D01*
X138101Y-820172D01*
G01X137396Y-817967D02*
X134890D01*
G01X140641Y-820172D02*
Y-813872D01*
X144245Y-820172D01*
Y-813872D01*
G01X18166Y-824397D02*
X17696Y-824082D01*
X17148Y-823872D01*
X16521D01*
X15816Y-824187D01*
X15268Y-824712D01*
X14876Y-825342D01*
X14563Y-826392D01*
X14485Y-827337D01*
X14641Y-828282D01*
X14876Y-828912D01*
X15346Y-829542D01*
X15895Y-829962D01*
X16443Y-830172D01*
X16991D01*
X17540Y-829962D01*
X18010Y-829647D01*
X18401Y-829227D01*
G01X21803Y-823872D02*
X23683D01*
G01X22743D02*
Y-830172D01*
G01X21803D02*
X23683D01*
G01X29043Y-823872D02*
Y-830172D01*
G01X27241Y-823872D02*
X30845D01*
G01X35343Y-830172D02*
Y-827337D01*
X33776Y-823872D01*
G01X36910D02*
X35343Y-827337D01*
G01X46220Y-828912D02*
X46690Y-829647D01*
X47316Y-830067D01*
X48021Y-830172D01*
X48648Y-830067D01*
X49275Y-829542D01*
X49666Y-828912D01*
X49745Y-828282D01*
X49588Y-827547D01*
X49040Y-827022D01*
X48491Y-826812D01*
X47786D01*
G01X48491D02*
X48961Y-826497D01*
X49353Y-825972D01*
X49510Y-825342D01*
X49353Y-824712D01*
X48961Y-824187D01*
X48256Y-823872D01*
X47551Y-823977D01*
X46846Y-824397D01*
G01X52520Y-828912D02*
X52990Y-829647D01*
X53616Y-830067D01*
X54321Y-830172D01*
X54948Y-830067D01*
X55575Y-829542D01*
X55966Y-828912D01*
X56045Y-828282D01*
X55888Y-827547D01*
X55340Y-827022D01*
X54791Y-826812D01*
X54086D01*
G01X54791D02*
X55261Y-826497D01*
X55653Y-825972D01*
X55810Y-825342D01*
X55653Y-824712D01*
X55261Y-824187D01*
X54556Y-823872D01*
X53851Y-823977D01*
X53146Y-824397D01*
G01X58820Y-828912D02*
X59290Y-829647D01*
X59916Y-830067D01*
X60621Y-830172D01*
X61248Y-830067D01*
X61875Y-829542D01*
X62266Y-828912D01*
X62345Y-828282D01*
X62188Y-827547D01*
X61640Y-827022D01*
X61091Y-826812D01*
X60386D01*
G01X61091D02*
X61561Y-826497D01*
X61953Y-825972D01*
X62110Y-825342D01*
X61953Y-824712D01*
X61561Y-824187D01*
X60856Y-823872D01*
X60151Y-823977D01*
X59446Y-824397D01*
G01X66686Y-830172D02*
X66843Y-828807D01*
X67078Y-827652D01*
X67391Y-826602D01*
X67783Y-825447D01*
X68410Y-823872D01*
X65276D01*
G01X72986Y-830172D02*
X73143Y-828807D01*
X73378Y-827652D01*
X73691Y-826602D01*
X74083Y-825447D01*
X74710Y-823872D01*
X71576D01*
G01X79286Y-831327D02*
X79600Y-829962D01*
G01X85743Y-823872D02*
Y-830172D01*
G01X83941Y-823872D02*
X87545D01*
G01X90085Y-830172D02*
X92043Y-823872D01*
X94001Y-830172D01*
G01X93296Y-827967D02*
X90790D01*
G01X97403Y-823872D02*
X99283D01*
G01X98343D02*
Y-830172D01*
G01X97403D02*
X99283D01*
G01X102293Y-823872D02*
X103390Y-830172D01*
X104643Y-823872D01*
X105896Y-830172D01*
X106993Y-823872D01*
G01X108985Y-830172D02*
X110943Y-823872D01*
X112901Y-830172D01*
G01X112196Y-827967D02*
X109690D01*
G01X115441Y-830172D02*
Y-823872D01*
X119045Y-830172D01*
Y-823872D01*
G01X129451Y-832272D02*
X128668Y-831222D01*
X128276Y-830172D01*
Y-825972D01*
X128668Y-824922D01*
X129451Y-823872D01*
G01X140876Y-830172D02*
Y-823872D01*
X142835D01*
X143461Y-824187D01*
X143853Y-824607D01*
X144010Y-825447D01*
X143853Y-826287D01*
X143383Y-826812D01*
X142835Y-827127D01*
X140876D01*
G01X142835D02*
X144010Y-830172D01*
G01X148743Y-830382D02*
X148586Y-830277D01*
Y-830067D01*
X148743Y-829962D01*
X148900Y-830067D01*
Y-830277D01*
X148743Y-830382D01*
G01X155043Y-830172D02*
X154416Y-830067D01*
X153868Y-829647D01*
X153398Y-829017D01*
X153085Y-828282D01*
X152928Y-827442D01*
Y-826602D01*
X153085Y-825762D01*
X153398Y-825027D01*
X153868Y-824397D01*
X154416Y-823977D01*
X155043Y-823872D01*
X155670Y-823977D01*
X156218Y-824397D01*
X156688Y-825027D01*
X157001Y-825762D01*
X157158Y-826602D01*
Y-827442D01*
X157001Y-828282D01*
X156688Y-829017D01*
X156218Y-829647D01*
X155670Y-830067D01*
X155043Y-830172D01*
G01X161343Y-830382D02*
X161186Y-830277D01*
Y-830067D01*
X161343Y-829962D01*
X161500Y-830067D01*
Y-830277D01*
X161343Y-830382D01*
G01X169366Y-824397D02*
X168896Y-824082D01*
X168348Y-823872D01*
X167721D01*
X167016Y-824187D01*
X166468Y-824712D01*
X166076Y-825342D01*
X165763Y-826392D01*
X165685Y-827337D01*
X165841Y-828282D01*
X166076Y-828912D01*
X166546Y-829542D01*
X167095Y-829962D01*
X167643Y-830172D01*
X168191D01*
X168740Y-829962D01*
X169210Y-829647D01*
X169601Y-829227D01*
G01X173943Y-830382D02*
X173786Y-830277D01*
Y-830067D01*
X173943Y-829962D01*
X174100Y-830067D01*
Y-830277D01*
X173943Y-830382D01*
G01X180635Y-832272D02*
X181418Y-831222D01*
X181810Y-830172D01*
Y-825972D01*
X181418Y-824922D01*
X180635Y-823872D01*
G01X38743Y-799472D02*
X36223Y-799055D01*
X34018Y-797389D01*
X32128Y-794889D01*
X30868Y-791972D01*
X30238Y-788639D01*
Y-785305D01*
X30868Y-781972D01*
X32128Y-779055D01*
X34018Y-776556D01*
X36223Y-774889D01*
X38743Y-774472D01*
X41263Y-774889D01*
X43468Y-776556D01*
X45358Y-779055D01*
X46618Y-781972D01*
X47248Y-785305D01*
Y-788639D01*
X46618Y-791972D01*
X45358Y-794889D01*
X43468Y-797389D01*
X41263Y-799055D01*
X38743Y-799472D01*
G01X41263Y-792805D02*
X45043Y-799472D01*
G01X58588Y-782806D02*
Y-794472D01*
X59848Y-797389D01*
X61738Y-799055D01*
X63943Y-799472D01*
X66148Y-799055D01*
X68038Y-797389D01*
X69298Y-794472D01*
G01Y-799472D02*
Y-782806D01*
G01X94813Y-799472D02*
Y-782806D01*
G01Y-785722D02*
X93553Y-784056D01*
X91663Y-783222D01*
X89458Y-782806D01*
X87253Y-783639D01*
X85363Y-785305D01*
X84103Y-787806D01*
X83473Y-791139D01*
X84103Y-794472D01*
X85363Y-796973D01*
X87253Y-798639D01*
X89458Y-799472D01*
X91663Y-799055D01*
X93553Y-797806D01*
X94813Y-796139D01*
G01X108988Y-799472D02*
Y-782806D01*
G01Y-786972D02*
X110248Y-784889D01*
X112138Y-783222D01*
X114658Y-782806D01*
X116863Y-783222D01*
X118753Y-784889D01*
X119698Y-787806D01*
Y-799472D01*
G01X139543Y-774472D02*
Y-799472D01*
G01X135133Y-782806D02*
X143953D01*
G01X170413Y-799472D02*
Y-782806D01*
G01Y-785722D02*
X169153Y-784056D01*
X167263Y-783222D01*
X165058Y-782806D01*
X162853Y-783639D01*
X160963Y-785305D01*
X159703Y-787806D01*
X159073Y-791139D01*
X159703Y-794472D01*
X160963Y-796973D01*
X162853Y-798639D01*
X165058Y-799472D01*
X167263Y-799055D01*
X169153Y-797806D01*
X170413Y-796139D01*
G01X14641Y-810172D02*
Y-803872D01*
X18245Y-810172D01*
Y-803872D01*
G01X22743Y-810172D02*
X22116Y-810067D01*
X21568Y-809647D01*
X21098Y-809017D01*
X20785Y-808282D01*
X20628Y-807442D01*
Y-806602D01*
X20785Y-805762D01*
X21098Y-805027D01*
X21568Y-804397D01*
X22116Y-803977D01*
X22743Y-803872D01*
X23370Y-803977D01*
X23918Y-804397D01*
X24388Y-805027D01*
X24701Y-805762D01*
X24858Y-806602D01*
Y-807442D01*
X24701Y-808282D01*
X24388Y-809017D01*
X23918Y-809647D01*
X23370Y-810067D01*
X22743Y-810172D01*
G01X29043Y-810382D02*
X28886Y-810277D01*
Y-810067D01*
X29043Y-809962D01*
X29200Y-810067D01*
Y-810277D01*
X29043Y-810382D01*
G01X33855Y-804922D02*
X34325Y-804292D01*
X34873Y-803977D01*
X35500Y-803872D01*
X36283Y-804082D01*
X36831Y-804607D01*
X36988Y-805237D01*
X36910Y-805867D01*
X36596Y-806392D01*
X35030Y-807442D01*
X34325Y-808177D01*
X33855Y-809227D01*
X33698Y-810172D01*
X36988D01*
G01X41643D02*
Y-803872D01*
X40703Y-805132D01*
G01Y-810172D02*
X42583D01*
G01X47943D02*
Y-803872D01*
X47003Y-805132D01*
G01Y-810172D02*
X48883D01*
G01X54086Y-811327D02*
X54400Y-809962D01*
G01X58193Y-803872D02*
X59290Y-810172D01*
X60543Y-803872D01*
X61796Y-810172D01*
X62893Y-803872D01*
G01X68410Y-810172D02*
X65276D01*
Y-803872D01*
X68410D01*
G01X67156Y-806917D02*
X65276D01*
G01X71341Y-810172D02*
Y-803872D01*
X74945Y-810172D01*
Y-803872D01*
G01X77798Y-810172D02*
Y-803872D01*
G01X81088D02*
Y-810172D01*
G01Y-807022D02*
X77798D01*
G01X84020Y-803872D02*
Y-808387D01*
X84333Y-809332D01*
X84960Y-809962D01*
X85743Y-810172D01*
X86526Y-809962D01*
X87153Y-809332D01*
X87466Y-808387D01*
Y-803872D01*
G01X90085Y-810172D02*
X92043Y-803872D01*
X94001Y-810172D01*
G01X93296Y-807967D02*
X90790D01*
G01X103155Y-804922D02*
X103625Y-804292D01*
X104173Y-803977D01*
X104800Y-803872D01*
X105583Y-804082D01*
X106131Y-804607D01*
X106288Y-805237D01*
X106210Y-805867D01*
X105896Y-806392D01*
X104330Y-807442D01*
X103625Y-808177D01*
X103155Y-809227D01*
X102998Y-810172D01*
X106288D01*
G01X109141D02*
Y-803872D01*
X112745Y-810172D01*
Y-803872D01*
G01X115520Y-810172D02*
Y-803872D01*
X117086D01*
X117713Y-804187D01*
X118183Y-804607D01*
X118575Y-805237D01*
X118888Y-805972D01*
X118966Y-807022D01*
X118888Y-808072D01*
X118575Y-808807D01*
X118183Y-809437D01*
X117713Y-809857D01*
X117086Y-810172D01*
X115520D01*
G01X128276D02*
Y-803872D01*
X130235D01*
X130861Y-804187D01*
X131253Y-804607D01*
X131410Y-805447D01*
X131253Y-806287D01*
X130783Y-806812D01*
X130235Y-807127D01*
X128276D01*
G01X130235D02*
X131410Y-810172D01*
G01X134420D02*
Y-803872D01*
X135986D01*
X136613Y-804187D01*
X137083Y-804607D01*
X137475Y-805237D01*
X137788Y-805972D01*
X137866Y-807022D01*
X137788Y-808072D01*
X137475Y-808807D01*
X137083Y-809437D01*
X136613Y-809857D01*
X135986Y-810172D01*
X134420D01*
G01X142443Y-810382D02*
X142286Y-810277D01*
Y-810067D01*
X142443Y-809962D01*
X142600Y-810067D01*
Y-810277D01*
X142443Y-810382D01*
G01X40945Y120689D02*
Y78759D01*
G01X63600Y265270D02*
X58600D01*
G01Y267930D02*
X63600D01*
G01X61100D02*
Y265270D01*
G01X63600Y270433D02*
X58600D01*
Y271953D01*
X58850Y272460D01*
X59433Y272840D01*
X60100Y272967D01*
X60767Y272840D01*
X61267Y272523D01*
X61517Y271953D01*
Y270433D01*
G01X63600Y275407D02*
X58600D01*
Y276673D01*
X58850Y277180D01*
X59183Y277560D01*
X59683Y277877D01*
X60267Y278130D01*
X61100Y278193D01*
X61933Y278130D01*
X62517Y277877D01*
X63017Y277560D01*
X63350Y277180D01*
X63600Y276673D01*
Y275407D01*
G01X60933Y282407D02*
X60683Y282660D01*
X60267Y282850D01*
X59683Y282977D01*
X59183Y282850D01*
X58850Y282597D01*
X58600Y282153D01*
Y280443D01*
X63600D01*
Y282533D01*
X63267Y282977D01*
X62767Y283230D01*
X62183Y283357D01*
X61600Y283230D01*
X61100Y282850D01*
X60933Y282407D01*
Y280443D01*
G01X59017Y293493D02*
X58767Y293113D01*
X58600Y292670D01*
Y292163D01*
X58850Y291593D01*
X59267Y291150D01*
X59767Y290833D01*
X60600Y290580D01*
X61350Y290517D01*
X62100Y290643D01*
X62600Y290833D01*
X63100Y291213D01*
X63433Y291657D01*
X63600Y292100D01*
Y292543D01*
X63433Y292987D01*
X63183Y293367D01*
X62850Y293683D01*
G01X63600Y297200D02*
X63517Y296693D01*
X63183Y296250D01*
X62683Y295870D01*
X62100Y295617D01*
X61433Y295490D01*
X60767D01*
X60100Y295617D01*
X59517Y295870D01*
X59017Y296250D01*
X58683Y296693D01*
X58600Y297200D01*
X58683Y297707D01*
X59017Y298150D01*
X59517Y298530D01*
X60100Y298783D01*
X60767Y298910D01*
X61433D01*
X62100Y298783D01*
X62683Y298530D01*
X63183Y298150D01*
X63517Y297707D01*
X63600Y297200D01*
G01Y300843D02*
X58600D01*
X63600Y303757D01*
X58600D01*
G01X63600Y305943D02*
X58600D01*
X63600Y308857D01*
X58600D01*
G01X51883Y385120D02*
X52075Y384810D01*
X52305Y384603D01*
X52573Y384500D01*
X52880Y384603D01*
X53110Y384810D01*
X53340Y385120D01*
X53417Y385533D01*
Y387600D01*
G01X55673Y384500D02*
X55750Y385172D01*
X55865Y385740D01*
X56018Y386257D01*
X56210Y386825D01*
X56517Y387600D01*
X54983D01*
G01X40945Y503170D02*
Y461240D01*
G01X67345Y19500D02*
Y22600D01*
G01X68955D02*
Y19500D01*
G01Y21050D02*
X67345D01*
G01X71250Y19500D02*
Y22600D01*
X70790Y21980D01*
G01Y19500D02*
X71710D01*
G01X73622Y20792D02*
X73890Y21153D01*
X74120Y21360D01*
X74427Y21463D01*
X74695Y21360D01*
X74887Y21153D01*
X75040Y20843D01*
X75078Y20482D01*
X75040Y20172D01*
X74887Y19862D01*
X74657Y19603D01*
X74388Y19500D01*
X74082Y19603D01*
X73813Y19913D01*
X73660Y20378D01*
X73622Y20895D01*
X73698Y21567D01*
X73813Y21928D01*
X74005Y22290D01*
X74273Y22548D01*
X74542Y22600D01*
X74810Y22497D01*
X75002Y22238D01*
G01X70845Y559000D02*
Y562100D01*
G01X72455D02*
Y559000D01*
G01Y560550D02*
X70845D01*
G01X74750Y559000D02*
Y562100D01*
X74290Y561480D01*
G01Y559000D02*
X75210D01*
G01X77850D02*
Y562100D01*
X77390Y561480D01*
G01Y559000D02*
X78310D01*
G01X116383Y124120D02*
X116575Y123810D01*
X116805Y123603D01*
X117073Y123500D01*
X117380Y123603D01*
X117610Y123810D01*
X117840Y124120D01*
X117917Y124533D01*
Y126600D01*
G01X120250Y123500D02*
Y126600D01*
X119790Y125980D01*
G01Y123500D02*
X120710D01*
G01X122507Y123965D02*
X122737Y123707D01*
X123005Y123552D01*
X123350Y123500D01*
X123695Y123603D01*
X123963Y123810D01*
X124155Y124172D01*
X124193Y124585D01*
X124117Y124998D01*
X123925Y125257D01*
X123657Y125463D01*
X123388Y125515D01*
X123120Y125463D01*
X122775Y125257D01*
X122890Y126600D01*
X123925D01*
G01X103187Y258000D02*
X105613D01*
G01X109907Y266000D02*
Y269100D01*
X110673D01*
X110980Y268945D01*
X111210Y268738D01*
X111402Y268428D01*
X111555Y268067D01*
X111593Y267550D01*
X111555Y267033D01*
X111402Y266672D01*
X111210Y266362D01*
X110980Y266155D01*
X110673Y266000D01*
X109907D01*
G01X113007Y266465D02*
X113237Y266207D01*
X113505Y266052D01*
X113850Y266000D01*
X114195Y266103D01*
X114463Y266310D01*
X114655Y266672D01*
X114693Y267085D01*
X114617Y267498D01*
X114425Y267757D01*
X114157Y267963D01*
X113888Y268015D01*
X113620Y267963D01*
X113275Y267757D01*
X113390Y269100D01*
X114425D01*
G01X109827Y264248D02*
X139386D01*
Y252752D01*
X109827D01*
Y264248D01*
G01X116383Y457120D02*
X116575Y456810D01*
X116805Y456603D01*
X117073Y456500D01*
X117380Y456603D01*
X117610Y456810D01*
X117840Y457120D01*
X117917Y457533D01*
Y459600D01*
G01X120250Y456500D02*
Y459600D01*
X119790Y458980D01*
G01Y456500D02*
X120710D01*
G01X123810D02*
Y459600D01*
X122392Y457378D01*
X124308D01*
G01X151667Y209893D02*
X151417Y210053D01*
X151292Y210240D01*
X151250Y210453D01*
X151333Y210720D01*
X151542Y210907D01*
X151792Y210960D01*
X152042Y210933D01*
X152250Y210827D01*
X152667Y210293D01*
X152958Y210053D01*
X153375Y209893D01*
X153750Y209840D01*
Y210960D01*
G01X151250Y212600D02*
X151333Y212387D01*
X151542Y212227D01*
X151792Y212120D01*
X152125Y212040D01*
X152500Y212013D01*
X152875Y212040D01*
X153208Y212120D01*
X153458Y212227D01*
X153667Y212387D01*
X153750Y212600D01*
X153667Y212813D01*
X153458Y212973D01*
X153208Y213080D01*
X152875Y213160D01*
X152500Y213187D01*
X152125Y213160D01*
X151792Y213080D01*
X151542Y212973D01*
X151333Y212813D01*
X151250Y212600D01*
G01X154780Y220460D02*
Y214260D01*
X151580D01*
Y220460D01*
X154780D01*
G01X140240Y230230D02*
Y236430D01*
X143440D01*
Y230230D01*
X140240D01*
G01X152750Y244900D02*
X150250D01*
X150750Y244580D01*
G01X152750D02*
Y245220D01*
G01X150667Y246593D02*
X150417Y246753D01*
X150292Y246940D01*
X150250Y247153D01*
X150333Y247420D01*
X150542Y247607D01*
X150792Y247660D01*
X151042Y247633D01*
X151250Y247527D01*
X151667Y246993D01*
X151958Y246753D01*
X152375Y246593D01*
X152750Y246540D01*
Y247660D01*
G01X156100Y251250D02*
Y248750D01*
X156420Y249250D01*
G01Y251250D02*
X155780D01*
G01X153900D02*
Y248750D01*
X154220Y249250D01*
G01Y251250D02*
X153580D01*
G01X154500Y243400D02*
Y233200D01*
X149900D01*
Y243400D01*
X154500D01*
G01X149300D02*
Y233200D01*
X144700D01*
Y243400D01*
X149300D01*
G01X151378Y492165D02*
Y262244D01*
X296260D01*
Y492165D01*
X151378D01*
G01X298228Y260275D02*
Y494133D01*
X149410D01*
Y260275D01*
X298228D01*
G01X143327Y263000D02*
X141087D01*
G01X142300Y261375D02*
Y264625D01*
G01X149623Y496004D02*
Y499104D01*
X150543D01*
X150850Y498949D01*
X151080Y498587D01*
X151157Y498174D01*
X151080Y497761D01*
X150888Y497451D01*
X150543Y497296D01*
X149623D01*
G01X152647Y499104D02*
Y496882D01*
X152800Y496417D01*
X153107Y496107D01*
X153490Y496004D01*
X153873Y496107D01*
X154180Y496417D01*
X154333Y496882D01*
Y499104D01*
G01X157050Y496004D02*
Y499104D01*
X155632Y496882D01*
X157548D01*
G01X184450Y100500D02*
G03I-9450J0D01*
G01X171345Y112500D02*
Y115600D01*
G01X172955D02*
Y112500D01*
G01Y114050D02*
X171345D01*
G01X174522Y115083D02*
X174752Y115393D01*
X175020Y115548D01*
X175327Y115600D01*
X175710Y115497D01*
X175978Y115238D01*
X176055Y114928D01*
X176017Y114618D01*
X175863Y114360D01*
X175097Y113843D01*
X174752Y113482D01*
X174522Y112965D01*
X174445Y112500D01*
X176055D01*
G01X178350D02*
Y115600D01*
X177890Y114980D01*
G01Y112500D02*
X178810D01*
G01X182940Y215230D02*
X176740D01*
Y218430D01*
X182940D01*
Y215230D01*
G01X176740Y222430D02*
X182940D01*
Y219230D01*
X176740D01*
Y222430D01*
G01X155157Y208550D02*
Y206328D01*
X155310Y205863D01*
X155617Y205553D01*
X156000Y205450D01*
X156383Y205553D01*
X156690Y205863D01*
X156843Y206328D01*
Y208550D01*
G01X158257Y206070D02*
X158487Y205708D01*
X158793Y205502D01*
X159138Y205450D01*
X159445Y205502D01*
X159752Y205760D01*
X159943Y206070D01*
X159982Y206380D01*
X159905Y206742D01*
X159637Y207000D01*
X159368Y207103D01*
X159023D01*
G01X159368D02*
X159598Y207258D01*
X159790Y207517D01*
X159867Y207827D01*
X159790Y208137D01*
X159598Y208395D01*
X159253Y208550D01*
X158908Y208498D01*
X158563Y208292D01*
G01X161472Y208033D02*
X161702Y208343D01*
X161970Y208498D01*
X162277Y208550D01*
X162660Y208447D01*
X162928Y208188D01*
X163005Y207878D01*
X162967Y207568D01*
X162813Y207310D01*
X162047Y206793D01*
X161702Y206432D01*
X161472Y205915D01*
X161395Y205450D01*
X163005D01*
G01X169307Y211850D02*
X169147Y211600D01*
X168960Y211475D01*
X168747Y211433D01*
X168480Y211516D01*
X168293Y211725D01*
X168240Y211975D01*
X168267Y212225D01*
X168373Y212433D01*
X168907Y212850D01*
X169147Y213141D01*
X169307Y213558D01*
X169360Y213933D01*
X168240D01*
G01X166600D02*
Y211433D01*
X166920Y211933D01*
G01Y213933D02*
X166280D01*
G01X165200Y214766D02*
X163600D01*
G01X162707Y211850D02*
X162547Y211600D01*
X162360Y211475D01*
X162147Y211433D01*
X161880Y211516D01*
X161693Y211725D01*
X161640Y211975D01*
X161667Y212225D01*
X161773Y212433D01*
X162307Y212850D01*
X162547Y213141D01*
X162707Y213558D01*
X162760Y213933D01*
X161640D01*
G01X160507Y211850D02*
X160347Y211600D01*
X160160Y211475D01*
X159947Y211433D01*
X159680Y211516D01*
X159493Y211725D01*
X159440Y211975D01*
X159467Y212225D01*
X159573Y212433D01*
X160107Y212850D01*
X160347Y213141D01*
X160507Y213558D01*
X160560Y213933D01*
X159440D01*
G01X163150Y216161D02*
X165050D01*
G01X157998Y217326D02*
Y216161D01*
G01X167061D02*
X170202D01*
Y217334D01*
G01X157998Y216161D02*
X161139D01*
G01X179671Y207976D02*
Y214176D01*
X182871D01*
Y207976D01*
X179671D01*
G01X176800Y226420D02*
X183000D01*
Y223220D01*
X176800D01*
Y226420D01*
G01X176740Y243930D02*
X182940D01*
Y240730D01*
X176740D01*
Y243930D01*
G01X157457Y242740D02*
X163657D01*
Y239540D01*
X157457D01*
Y242740D01*
G01X168440Y240730D02*
Y246930D01*
X171640D01*
Y240730D01*
X168440D01*
G01X167640Y246930D02*
Y240730D01*
X164440D01*
Y246930D01*
X167640D01*
G01X176740Y232930D02*
X182940D01*
Y229730D01*
X176740D01*
Y232930D01*
G01Y239930D02*
X182940D01*
Y236730D01*
X176740D01*
Y239930D01*
G01X157457Y250740D02*
X163657D01*
Y247540D01*
X157457D01*
Y250740D01*
G01Y246760D02*
X163657D01*
Y243560D01*
X157457D01*
Y246760D01*
G01X170800Y240133D02*
Y237633D01*
X171120Y238133D01*
G01Y240133D02*
X170480D01*
G01X168600Y237633D02*
X168813Y237716D01*
X168973Y237925D01*
X169080Y238175D01*
X169160Y238508D01*
X169187Y238883D01*
X169160Y239258D01*
X169080Y239591D01*
X168973Y239841D01*
X168813Y240050D01*
X168600Y240133D01*
X168387Y240050D01*
X168227Y239841D01*
X168120Y239591D01*
X168040Y239258D01*
X168013Y238883D01*
X168040Y238508D01*
X168120Y238175D01*
X168227Y237925D01*
X168387Y237716D01*
X168600Y237633D01*
G01X174141Y235947D02*
X174350Y236133D01*
X174433Y236347D01*
X174350Y236560D01*
X174100Y236747D01*
X173725Y236880D01*
X173350Y236933D01*
X172891D01*
X172516Y236880D01*
X172183Y236747D01*
X172016Y236587D01*
X171933Y236400D01*
X172016Y236187D01*
X172183Y236027D01*
X172433Y235920D01*
X172766Y235867D01*
X173058Y235920D01*
X173350Y236053D01*
X173516Y236213D01*
X173558Y236400D01*
X173475Y236613D01*
X173266Y236773D01*
X172891Y236933D01*
G01X161132Y236239D02*
X157998D01*
Y235074D01*
G01X165068Y236239D02*
X163132D01*
G01X170202Y235074D02*
Y236239D01*
X167068D01*
G01X184739Y507200D02*
Y499800D01*
X167339D01*
Y507200D01*
X184739D01*
G01Y516200D02*
Y508800D01*
X167339D01*
Y516200D01*
X184739D01*
G01X196082Y539000D02*
G03I-20700J0D01*
G01X175381Y559700D02*
Y518300D01*
G01X170383Y561500D02*
Y564600D01*
X171303D01*
X171610Y564445D01*
X171840Y564083D01*
X171917Y563670D01*
X171840Y563257D01*
X171648Y562947D01*
X171303Y562792D01*
X170383D01*
G01X175093Y564342D02*
X174863Y564497D01*
X174595Y564600D01*
X174288D01*
X173943Y564445D01*
X173675Y564187D01*
X173483Y563877D01*
X173330Y563360D01*
X173292Y562895D01*
X173368Y562430D01*
X173483Y562120D01*
X173713Y561810D01*
X173982Y561603D01*
X174250Y561500D01*
X174518D01*
X174787Y561603D01*
X175017Y561758D01*
X175208Y561965D01*
G01X177273Y561500D02*
X177350Y562172D01*
X177465Y562740D01*
X177618Y563257D01*
X177810Y563825D01*
X178117Y564600D01*
X176583D01*
G01X179607Y562120D02*
X179837Y561758D01*
X180143Y561552D01*
X180488Y561500D01*
X180795Y561552D01*
X181102Y561810D01*
X181293Y562120D01*
X181332Y562430D01*
X181255Y562792D01*
X180987Y563050D01*
X180718Y563153D01*
X180373D01*
G01X180718D02*
X180948Y563308D01*
X181140Y563567D01*
X181217Y563877D01*
X181140Y564187D01*
X180948Y564445D01*
X180603Y564600D01*
X180258Y564548D01*
X179913Y564342D01*
G01X210093Y-779172D02*
Y-787172D01*
X214093D01*
G01X221893D02*
Y-781839D01*
G01Y-782772D02*
X221493Y-782239D01*
X220893Y-781972D01*
X220193Y-781839D01*
X219493Y-782105D01*
X218893Y-782639D01*
X218493Y-783439D01*
X218293Y-784505D01*
X218493Y-785572D01*
X218893Y-786372D01*
X219493Y-786905D01*
X220193Y-787172D01*
X220893Y-787039D01*
X221493Y-786639D01*
X221893Y-786106D01*
G01X225993Y-789572D02*
X226593Y-789839D01*
X227393Y-789572D01*
X227893Y-789039D01*
X228293Y-788372D01*
X228893Y-786239D01*
X230193Y-781839D01*
G01X226993D02*
X228893Y-786239D01*
G01X234593Y-783572D02*
X237793D01*
X237493Y-782639D01*
X236993Y-782105D01*
X236293Y-781839D01*
X235593Y-781972D01*
X234993Y-782372D01*
X234593Y-783305D01*
X234393Y-784106D01*
Y-784905D01*
X234593Y-785705D01*
X235093Y-786505D01*
X235693Y-787039D01*
X236393Y-787172D01*
X237093Y-786905D01*
X237793Y-786106D01*
G01X242693Y-787172D02*
Y-781839D01*
G01Y-782905D02*
X243193Y-782372D01*
X243693Y-781972D01*
X244393Y-781839D01*
X244893Y-781972D01*
X245493Y-782372D01*
G01X193933Y59500D02*
Y67000D01*
X196173D01*
X196920Y66625D01*
X197480Y65750D01*
X197667Y64750D01*
X197480Y63750D01*
X197013Y63000D01*
X196173Y62625D01*
X193933D01*
G01X201620Y59250D02*
X204980Y67000D01*
G01X208653Y59500D02*
Y67000D01*
X212947Y59500D01*
Y67000D01*
G01X218300Y59250D02*
X218113Y59375D01*
Y59625D01*
X218300Y59750D01*
X218487Y59625D01*
Y59375D01*
X218300Y59250D01*
G01Y62625D02*
X218113Y62750D01*
Y63000D01*
X218300Y63125D01*
X218487Y63000D01*
Y62750D01*
X218300Y62625D01*
G01X223747Y59500D02*
Y67000D01*
X225613D01*
X226360Y66625D01*
X226920Y66125D01*
X227387Y65375D01*
X227760Y64500D01*
X227853Y63250D01*
X227760Y62000D01*
X227387Y61125D01*
X226920Y60375D01*
X226360Y59875D01*
X225613Y59500D01*
X223747D01*
G01X230967D02*
X233300Y67000D01*
X235633Y59500D01*
G01X234793Y62125D02*
X231807D01*
G01X240800Y67000D02*
X240053Y66750D01*
X239493Y66125D01*
X239120Y65375D01*
X238840Y64375D01*
X238747Y63250D01*
X238840Y62125D01*
X239120Y61125D01*
X239493Y60375D01*
X240053Y59750D01*
X240800Y59500D01*
X241547Y59750D01*
X242107Y60375D01*
X242480Y61125D01*
X242760Y62125D01*
X242853Y63250D01*
X242760Y64375D01*
X242480Y65375D01*
X242107Y66125D01*
X241547Y66750D01*
X240800Y67000D01*
G01X246527Y59500D02*
Y67000D01*
X250073D01*
G01X248767Y63375D02*
X246527D01*
G01X255800Y67000D02*
X255053Y66750D01*
X254493Y66125D01*
X254120Y65375D01*
X253840Y64375D01*
X253747Y63250D01*
X253840Y62125D01*
X254120Y61125D01*
X254493Y60375D01*
X255053Y59750D01*
X255800Y59500D01*
X256547Y59750D01*
X257107Y60375D01*
X257480Y61125D01*
X257760Y62125D01*
X257853Y63250D01*
X257760Y64375D01*
X257480Y65375D01*
X257107Y66125D01*
X256547Y66750D01*
X255800Y67000D01*
G01X263300D02*
Y59500D01*
G01X261153Y67000D02*
X265447D01*
G01X268933Y59500D02*
Y67000D01*
X271173D01*
X271920Y66625D01*
X272480Y65750D01*
X272667Y64750D01*
X272480Y63750D01*
X272013Y63000D01*
X271173Y62625D01*
X268933D01*
G01X279047Y63500D02*
X279420Y63875D01*
X279700Y64500D01*
X279887Y65375D01*
X279700Y66125D01*
X279327Y66625D01*
X278673Y67000D01*
X276153D01*
Y59500D01*
X279233D01*
X279887Y60000D01*
X280260Y60750D01*
X280447Y61625D01*
X280260Y62500D01*
X279700Y63250D01*
X279047Y63500D01*
X276153D01*
G01X283467Y59500D02*
X285800Y67000D01*
X288133Y59500D01*
G01X287293Y62125D02*
X284307D01*
G01X291527Y59500D02*
Y67000D01*
X295073D01*
G01X293767Y63375D02*
X291527D01*
G01X300800Y67000D02*
X300053Y66750D01*
X299493Y66125D01*
X299120Y65375D01*
X298840Y64375D01*
X298747Y63250D01*
X298840Y62125D01*
X299120Y61125D01*
X299493Y60375D01*
X300053Y59750D01*
X300800Y59500D01*
X301547Y59750D01*
X302107Y60375D01*
X302480Y61125D01*
X302760Y62125D01*
X302853Y63250D01*
X302760Y64375D01*
X302480Y65375D01*
X302107Y66125D01*
X301547Y66750D01*
X300800Y67000D01*
G01X194000Y45000D02*
Y53000D01*
X196500D01*
X197300Y52600D01*
X197800Y52067D01*
X198000Y51000D01*
X197800Y49933D01*
X197200Y49267D01*
X196500Y48867D01*
X194000D01*
G01X196500D02*
X198000Y45000D01*
G01X202500Y48600D02*
X205700D01*
X205400Y49533D01*
X204900Y50067D01*
X204200Y50333D01*
X203500Y50200D01*
X202900Y49800D01*
X202500Y48867D01*
X202300Y48066D01*
Y47267D01*
X202500Y46467D01*
X203000Y45667D01*
X203600Y45133D01*
X204300Y45000D01*
X205000Y45267D01*
X205700Y46066D01*
G01X210200Y50333D02*
X212000Y45000D01*
X213800Y50333D01*
G01X220000Y44733D02*
X219800Y44867D01*
Y45133D01*
X220000Y45267D01*
X220200Y45133D01*
Y44867D01*
X220000Y44733D01*
G01Y48333D02*
X219800Y48467D01*
Y48733D01*
X220000Y48867D01*
X220200Y48733D01*
Y48467D01*
X220000Y48333D01*
G01X226100Y45000D02*
Y53000D01*
X229900D01*
G01X228500Y49133D02*
X226100D01*
G01X189644Y238096D02*
Y207004D01*
X205156D01*
Y238096D01*
X189644D01*
G01X203807Y239500D02*
Y242600D01*
X204573D01*
X204880Y242445D01*
X205110Y242238D01*
X205302Y241928D01*
X205455Y241567D01*
X205493Y241050D01*
X205455Y240533D01*
X205302Y240172D01*
X205110Y239862D01*
X204880Y239655D01*
X204573Y239500D01*
X203807D01*
G01X208210D02*
Y242600D01*
X206792Y240378D01*
X208708D01*
G01X244082Y539000D02*
G03I-20701J0D01*
G01X229193Y-829172D02*
X232993D01*
X229193Y-837172D01*
X232993D01*
G01X239093Y-831839D02*
Y-837172D01*
G01Y-829705D02*
X238893Y-829572D01*
Y-829305D01*
X239093Y-829172D01*
X239293Y-829305D01*
Y-829572D01*
X239093Y-829705D01*
G01X245793Y-834505D02*
X248393D01*
G01X253093Y-837172D02*
Y-829172D01*
X255493D01*
X256293Y-829572D01*
X256893Y-830505D01*
X257093Y-831572D01*
X256893Y-832639D01*
X256393Y-833439D01*
X255493Y-833839D01*
X253093D01*
G01X263093Y-831839D02*
Y-837172D01*
G01Y-829705D02*
X262893Y-829572D01*
Y-829305D01*
X263093Y-829172D01*
X263293Y-829305D01*
Y-829572D01*
X263093Y-829705D01*
G01X269393Y-837172D02*
Y-831839D01*
G01Y-833172D02*
X269793Y-832505D01*
X270393Y-831972D01*
X271193Y-831839D01*
X271893Y-831972D01*
X272493Y-832505D01*
X272793Y-833439D01*
Y-837172D01*
G01X277693Y-839172D02*
X278393Y-839705D01*
X279193Y-839839D01*
X279893Y-839705D01*
X280493Y-839039D01*
X280893Y-838105D01*
Y-831839D01*
G01Y-832905D02*
X280493Y-832372D01*
X279893Y-831972D01*
X279193Y-831839D01*
X278393Y-832105D01*
X277893Y-832639D01*
X277493Y-833572D01*
X277293Y-834505D01*
X277393Y-835305D01*
X277793Y-836239D01*
X278393Y-836905D01*
X279193Y-837172D01*
X279793Y-837039D01*
X280493Y-836505D01*
X280893Y-835972D01*
G01X221493Y-811106D02*
X222293Y-811772D01*
X223193Y-812172D01*
X223993D01*
X224793Y-811772D01*
X225393Y-811106D01*
X225693Y-810172D01*
X225493Y-809239D01*
X224993Y-808439D01*
X224093Y-807905D01*
X222893Y-807639D01*
X222193Y-807105D01*
X221893Y-806172D01*
X222093Y-805239D01*
X222593Y-804572D01*
X223293Y-804172D01*
X223993D01*
X224693Y-804439D01*
X225293Y-805105D01*
G01X230393Y-804172D02*
X232793D01*
G01X231593D02*
Y-812172D01*
G01X230393D02*
X232793D01*
G01X237593Y-804172D02*
Y-812172D01*
X241593D01*
G01X245393D02*
Y-804172D01*
G01X249193D02*
X245393Y-809106D01*
G01X249793Y-812172D02*
X247093Y-806839D01*
G01X254293Y-809505D02*
X256893D01*
G01X263593Y-804172D02*
Y-812172D01*
G01X261293Y-804172D02*
X265893D01*
G01X271593Y-812172D02*
X270793Y-812039D01*
X270093Y-811505D01*
X269493Y-810705D01*
X269093Y-809772D01*
X268893Y-808705D01*
Y-807639D01*
X269093Y-806572D01*
X269493Y-805639D01*
X270093Y-804839D01*
X270793Y-804305D01*
X271593Y-804172D01*
X272393Y-804305D01*
X273093Y-804839D01*
X273693Y-805639D01*
X274093Y-806572D01*
X274293Y-807639D01*
Y-808705D01*
X274093Y-809772D01*
X273693Y-810705D01*
X273093Y-811505D01*
X272393Y-812039D01*
X271593Y-812172D01*
G01X277593D02*
Y-804172D01*
X279993D01*
X280793Y-804572D01*
X281393Y-805505D01*
X281593Y-806572D01*
X281393Y-807639D01*
X280893Y-808439D01*
X279993Y-808839D01*
X277593D01*
G01X226457Y104173D02*
Y185197D01*
X552047D01*
Y104173D01*
X226457D01*
G01X540236Y122085D02*
Y115984D01*
X238268D01*
G01D02*
Y122035D01*
G01Y137335D02*
Y173386D01*
X540236D01*
Y137335D01*
G01X231500Y233700D02*
Y240300D01*
X244500D01*
Y233700D01*
X231500D01*
G01X234900Y244600D02*
X241100D01*
Y241400D01*
X234900D01*
Y244600D01*
G01Y249100D02*
X241100D01*
Y245900D01*
X234900D01*
Y249100D01*
G01X232739Y516200D02*
Y508800D01*
X215339D01*
Y516200D01*
X232739D01*
G01Y507200D02*
Y499800D01*
X215339D01*
Y507200D01*
X232739D01*
G01X223381Y559700D02*
Y518300D01*
G01X217883Y561500D02*
Y564600D01*
X218803D01*
X219110Y564445D01*
X219340Y564083D01*
X219417Y563670D01*
X219340Y563257D01*
X219148Y562947D01*
X218803Y562792D01*
X217883D01*
G01X222593Y564342D02*
X222363Y564497D01*
X222095Y564600D01*
X221788D01*
X221443Y564445D01*
X221175Y564187D01*
X220983Y563877D01*
X220830Y563360D01*
X220792Y562895D01*
X220868Y562430D01*
X220983Y562120D01*
X221213Y561810D01*
X221482Y561603D01*
X221750Y561500D01*
X222018D01*
X222287Y561603D01*
X222517Y561758D01*
X222708Y561965D01*
G01X224773Y561500D02*
X224850Y562172D01*
X224965Y562740D01*
X225118Y563257D01*
X225310Y563825D01*
X225617Y564600D01*
X224083D01*
G01X227222Y564083D02*
X227452Y564393D01*
X227720Y564548D01*
X228027Y564600D01*
X228410Y564497D01*
X228678Y564238D01*
X228755Y563928D01*
X228717Y563618D01*
X228563Y563360D01*
X227797Y562843D01*
X227452Y562482D01*
X227222Y561965D01*
X227145Y561500D01*
X228755D01*
G01X245000Y53185D02*
X351299D01*
Y29563D01*
X245000D01*
Y53185D01*
G01X247355Y43707D02*
Y51207D01*
X249595D01*
X250342Y50832D01*
X250902Y49957D01*
X251089Y48957D01*
X250902Y47957D01*
X250435Y47207D01*
X249595Y46832D01*
X247355D01*
G01X255042Y43457D02*
X258402Y51207D01*
G01X262075Y43707D02*
Y51207D01*
X266369Y43707D01*
Y51207D01*
G01X251000Y53185D02*
X245000D01*
G01D02*
Y47185D01*
G01X288700Y230158D02*
G03I-20700J-1D01*
G01D02*
X247300D01*
G01X263383Y252500D02*
Y255600D01*
X264303D01*
X264610Y255445D01*
X264840Y255083D01*
X264917Y254670D01*
X264840Y254257D01*
X264648Y253947D01*
X264303Y253792D01*
X263383D01*
G01X268093Y255342D02*
X267863Y255497D01*
X267595Y255600D01*
X267288D01*
X266943Y255445D01*
X266675Y255187D01*
X266483Y254877D01*
X266330Y254360D01*
X266292Y253895D01*
X266368Y253430D01*
X266483Y253120D01*
X266713Y252810D01*
X266982Y252603D01*
X267250Y252500D01*
X267518D01*
X267787Y252603D01*
X268017Y252758D01*
X268208Y252965D01*
G01X269698Y252862D02*
X269967Y252603D01*
X270273Y252500D01*
X270580Y252603D01*
X270848Y252913D01*
X271040Y253378D01*
X271117Y253843D01*
Y254412D01*
X271040Y254877D01*
X270848Y255290D01*
X270618Y255497D01*
X270350Y255600D01*
X270043Y255497D01*
X269813Y255290D01*
X269660Y254980D01*
X269583Y254567D01*
X269660Y254205D01*
X269852Y253843D01*
X270082Y253637D01*
X270350Y253585D01*
X270657Y253688D01*
X270887Y253947D01*
X271117Y254412D01*
G01X273450Y252500D02*
X273718Y252552D01*
X274025Y252707D01*
X274217Y252965D01*
X274293Y253327D01*
X274217Y253688D01*
X273987Y253998D01*
X273642Y254153D01*
X273258D01*
X273028Y254257D01*
X272837Y254515D01*
X272760Y254877D01*
X272875Y255238D01*
X273143Y255497D01*
X273450Y255600D01*
X273757Y255497D01*
X274025Y255238D01*
X274140Y254877D01*
X274063Y254515D01*
X273872Y254257D01*
X273642Y254153D01*
X273258D01*
X272913Y253998D01*
X272683Y253688D01*
X272607Y253327D01*
X272683Y252965D01*
X272875Y252707D01*
X273182Y252552D01*
X273450Y252500D01*
G01X280739Y507200D02*
Y499800D01*
X263339D01*
Y507200D01*
X280739D01*
G01Y516200D02*
Y508800D01*
X263339D01*
Y516200D01*
X280739D01*
G01X292082Y539000D02*
G03I-20701J0D01*
G01X271381Y559700D02*
Y518300D01*
G01X266383Y562000D02*
Y565100D01*
X267303D01*
X267610Y564945D01*
X267840Y564583D01*
X267917Y564170D01*
X267840Y563757D01*
X267648Y563447D01*
X267303Y563292D01*
X266383D01*
G01X271093Y564842D02*
X270863Y564997D01*
X270595Y565100D01*
X270288D01*
X269943Y564945D01*
X269675Y564687D01*
X269483Y564377D01*
X269330Y563860D01*
X269292Y563395D01*
X269368Y562930D01*
X269483Y562620D01*
X269713Y562310D01*
X269982Y562103D01*
X270250Y562000D01*
X270518D01*
X270787Y562103D01*
X271017Y562258D01*
X271208Y562465D01*
G01X273273Y562000D02*
X273350Y562672D01*
X273465Y563240D01*
X273618Y563757D01*
X273810Y564325D01*
X274117Y565100D01*
X272583D01*
G01X276450Y562000D02*
Y565100D01*
X275990Y564480D01*
G01Y562000D02*
X276910D01*
G01X296000Y207500D02*
Y201500D01*
X284000D01*
Y207500D01*
X296000D01*
G01Y199500D02*
Y193500D01*
X284000D01*
Y199500D01*
X296000D01*
G01X333200Y230158D02*
G03I-20700J-1D01*
G01D02*
X291800D01*
G01X339000Y207500D02*
Y201500D01*
X327000D01*
Y207500D01*
X339000D01*
G01Y199500D02*
Y193500D01*
X327000D01*
Y199500D01*
X339000D01*
G01X317500Y207500D02*
Y201500D01*
X305500D01*
Y207500D01*
X317500D01*
G01Y199500D02*
Y193500D01*
X305500D01*
Y199500D01*
X317500D01*
G01X308858Y492165D02*
Y262244D01*
X453740D01*
Y492165D01*
X308858D01*
G01X455708Y260275D02*
Y494133D01*
X306890D01*
Y260275D01*
X455708D01*
G01X306883Y252500D02*
Y255600D01*
X307803D01*
X308110Y255445D01*
X308340Y255083D01*
X308417Y254670D01*
X308340Y254257D01*
X308148Y253947D01*
X307803Y253792D01*
X306883D01*
G01X311593Y255342D02*
X311363Y255497D01*
X311095Y255600D01*
X310788D01*
X310443Y255445D01*
X310175Y255187D01*
X309983Y254877D01*
X309830Y254360D01*
X309792Y253895D01*
X309868Y253430D01*
X309983Y253120D01*
X310213Y252810D01*
X310482Y252603D01*
X310750Y252500D01*
X311018D01*
X311287Y252603D01*
X311517Y252758D01*
X311708Y252965D01*
G01X313198Y252862D02*
X313467Y252603D01*
X313773Y252500D01*
X314080Y252603D01*
X314348Y252913D01*
X314540Y253378D01*
X314617Y253843D01*
Y254412D01*
X314540Y254877D01*
X314348Y255290D01*
X314118Y255497D01*
X313850Y255600D01*
X313543Y255497D01*
X313313Y255290D01*
X313160Y254980D01*
X313083Y254567D01*
X313160Y254205D01*
X313352Y253843D01*
X313582Y253637D01*
X313850Y253585D01*
X314157Y253688D01*
X314387Y253947D01*
X314617Y254412D01*
G01X316873Y252500D02*
X316950Y253172D01*
X317065Y253740D01*
X317218Y254257D01*
X317410Y254825D01*
X317717Y255600D01*
X316183D01*
G01X307103Y496004D02*
Y499104D01*
X308023D01*
X308330Y498949D01*
X308560Y498587D01*
X308637Y498174D01*
X308560Y497761D01*
X308368Y497451D01*
X308023Y497296D01*
X307103D01*
G01X310127Y499104D02*
Y496882D01*
X310280Y496417D01*
X310587Y496107D01*
X310970Y496004D01*
X311353Y496107D01*
X311660Y496417D01*
X311813Y496882D01*
Y499104D01*
G01X313227Y496624D02*
X313457Y496262D01*
X313763Y496056D01*
X314108Y496004D01*
X314415Y496056D01*
X314722Y496314D01*
X314913Y496624D01*
X314952Y496934D01*
X314875Y497296D01*
X314607Y497554D01*
X314338Y497657D01*
X313993D01*
G01X314338D02*
X314568Y497812D01*
X314760Y498071D01*
X314837Y498381D01*
X314760Y498691D01*
X314568Y498949D01*
X314223Y499104D01*
X313878Y499052D01*
X313533Y498846D01*
G01X342219Y507200D02*
Y499800D01*
X324819D01*
Y507200D01*
X342219D01*
G01Y516200D02*
Y508800D01*
X324819D01*
Y516200D01*
X342219D01*
G01X353562Y539000D02*
G03I-20701J0D01*
G01X327383Y561500D02*
Y564600D01*
X328303D01*
X328610Y564445D01*
X328840Y564083D01*
X328917Y563670D01*
X328840Y563257D01*
X328648Y562947D01*
X328303Y562792D01*
X327383D01*
G01X332093Y564342D02*
X331863Y564497D01*
X331595Y564600D01*
X331288D01*
X330943Y564445D01*
X330675Y564187D01*
X330483Y563877D01*
X330330Y563360D01*
X330292Y562895D01*
X330368Y562430D01*
X330483Y562120D01*
X330713Y561810D01*
X330982Y561603D01*
X331250Y561500D01*
X331518D01*
X331787Y561603D01*
X332017Y561758D01*
X332208Y561965D01*
G01X334810Y561500D02*
Y564600D01*
X333392Y562378D01*
X335308D01*
G01X336607Y561965D02*
X336837Y561707D01*
X337105Y561552D01*
X337450Y561500D01*
X337795Y561603D01*
X338063Y561810D01*
X338255Y562172D01*
X338293Y562585D01*
X338217Y562998D01*
X338025Y563257D01*
X337757Y563463D01*
X337488Y563515D01*
X337220Y563463D01*
X336875Y563257D01*
X336990Y564600D01*
X338025D01*
G01X336693Y-830505D02*
X337293Y-829705D01*
X337993Y-829305D01*
X338793Y-829172D01*
X339793Y-829439D01*
X340493Y-830105D01*
X340693Y-830905D01*
X340593Y-831706D01*
X340193Y-832372D01*
X338193Y-833705D01*
X337293Y-834639D01*
X336693Y-835972D01*
X336493Y-837172D01*
X340693D01*
G01X346593Y-829172D02*
X345793Y-829439D01*
X345193Y-830105D01*
X344793Y-830905D01*
X344493Y-831972D01*
X344393Y-833172D01*
X344493Y-834372D01*
X344793Y-835439D01*
X345193Y-836239D01*
X345793Y-836905D01*
X346593Y-837172D01*
X347393Y-836905D01*
X347993Y-836239D01*
X348393Y-835439D01*
X348693Y-834372D01*
X348793Y-833172D01*
X348693Y-831972D01*
X348393Y-830905D01*
X347993Y-830105D01*
X347393Y-829439D01*
X346593Y-829172D01*
G01X352693Y-830505D02*
X353293Y-829705D01*
X353993Y-829305D01*
X354793Y-829172D01*
X355793Y-829439D01*
X356493Y-830105D01*
X356693Y-830905D01*
X356593Y-831706D01*
X356193Y-832372D01*
X354193Y-833705D01*
X353293Y-834639D01*
X352693Y-835972D01*
X352493Y-837172D01*
X356693D01*
G01X360693Y-830505D02*
X361293Y-829705D01*
X361993Y-829305D01*
X362793Y-829172D01*
X363793Y-829439D01*
X364493Y-830105D01*
X364693Y-830905D01*
X364593Y-831706D01*
X364193Y-832372D01*
X362193Y-833705D01*
X361293Y-834639D01*
X360693Y-835972D01*
X360493Y-837172D01*
X364693D01*
G01X368793Y-837439D02*
X372393Y-829172D01*
G01X378593Y-837172D02*
Y-829172D01*
X377393Y-830772D01*
G01Y-837172D02*
X379793D01*
G01X384693Y-830505D02*
X385293Y-829705D01*
X385993Y-829305D01*
X386793Y-829172D01*
X387793Y-829439D01*
X388493Y-830105D01*
X388693Y-830905D01*
X388593Y-831706D01*
X388193Y-832372D01*
X386193Y-833705D01*
X385293Y-834639D01*
X384693Y-835972D01*
X384493Y-837172D01*
X388693D01*
G01X392793Y-837439D02*
X396393Y-829172D01*
G01X402593D02*
X401793Y-829439D01*
X401193Y-830105D01*
X400793Y-830905D01*
X400493Y-831972D01*
X400393Y-833172D01*
X400493Y-834372D01*
X400793Y-835439D01*
X401193Y-836239D01*
X401793Y-836905D01*
X402593Y-837172D01*
X403393Y-836905D01*
X403993Y-836239D01*
X404393Y-835439D01*
X404693Y-834372D01*
X404793Y-833172D01*
X404693Y-831972D01*
X404393Y-830905D01*
X403993Y-830105D01*
X403393Y-829439D01*
X402593Y-829172D01*
G01X408693Y-830505D02*
X409293Y-829705D01*
X409993Y-829305D01*
X410793Y-829172D01*
X411793Y-829439D01*
X412493Y-830105D01*
X412693Y-830905D01*
X412593Y-831706D01*
X412193Y-832372D01*
X410193Y-833705D01*
X409293Y-834639D01*
X408693Y-835972D01*
X408493Y-837172D01*
X412693D01*
G01X336393Y-814672D02*
Y-806672D01*
X338393D01*
X339193Y-807072D01*
X339793Y-807605D01*
X340293Y-808405D01*
X340693Y-809339D01*
X340793Y-810672D01*
X340693Y-812005D01*
X340293Y-812939D01*
X339793Y-813739D01*
X339193Y-814272D01*
X338393Y-814672D01*
X336393D01*
G01X344093D02*
X346593Y-806672D01*
X349093Y-814672D01*
G01X348193Y-811872D02*
X344993D01*
G01X354593Y-806672D02*
X353793Y-806939D01*
X353193Y-807605D01*
X352793Y-808405D01*
X352493Y-809472D01*
X352393Y-810672D01*
X352493Y-811872D01*
X352793Y-812939D01*
X353193Y-813739D01*
X353793Y-814405D01*
X354593Y-814672D01*
X355393Y-814405D01*
X355993Y-813739D01*
X356393Y-812939D01*
X356693Y-811872D01*
X356793Y-810672D01*
X356693Y-809472D01*
X356393Y-808405D01*
X355993Y-807605D01*
X355393Y-806939D01*
X354593Y-806672D01*
G01X360693Y-814672D02*
Y-806672D01*
X364493D01*
G01X363093Y-810539D02*
X360693D01*
G01X370593Y-806672D02*
X369793Y-806939D01*
X369193Y-807605D01*
X368793Y-808405D01*
X368493Y-809472D01*
X368393Y-810672D01*
X368493Y-811872D01*
X368793Y-812939D01*
X369193Y-813739D01*
X369793Y-814405D01*
X370593Y-814672D01*
X371393Y-814405D01*
X371993Y-813739D01*
X372393Y-812939D01*
X372693Y-811872D01*
X372793Y-810672D01*
X372693Y-809472D01*
X372393Y-808405D01*
X371993Y-807605D01*
X371393Y-806939D01*
X370593Y-806672D01*
G01X378593D02*
Y-814672D01*
G01X376293Y-806672D02*
X380893D01*
G01X384593Y-814672D02*
Y-806672D01*
X386993D01*
X387793Y-807072D01*
X388393Y-808005D01*
X388593Y-809072D01*
X388393Y-810139D01*
X387893Y-810939D01*
X386993Y-811339D01*
X384593D01*
G01X395393Y-810405D02*
X395793Y-810005D01*
X396093Y-809339D01*
X396293Y-808405D01*
X396093Y-807605D01*
X395693Y-807072D01*
X394993Y-806672D01*
X392293D01*
Y-814672D01*
X395593D01*
X396293Y-814139D01*
X396693Y-813339D01*
X396893Y-812405D01*
X396693Y-811472D01*
X396093Y-810672D01*
X395393Y-810405D01*
X392293D01*
G01X400093Y-814672D02*
X402593Y-806672D01*
X405093Y-814672D01*
G01X404193Y-811872D02*
X400993D01*
G01X408693Y-814672D02*
Y-806672D01*
X412493D01*
G01X411093Y-810539D02*
X408693D01*
G01X418593Y-806672D02*
X417793Y-806939D01*
X417193Y-807605D01*
X416793Y-808405D01*
X416493Y-809472D01*
X416393Y-810672D01*
X416493Y-811872D01*
X416793Y-812939D01*
X417193Y-813739D01*
X417793Y-814405D01*
X418593Y-814672D01*
X419393Y-814405D01*
X419993Y-813739D01*
X420393Y-812939D01*
X420693Y-811872D01*
X420793Y-810672D01*
X420693Y-809472D01*
X420393Y-808405D01*
X419993Y-807605D01*
X419393Y-806939D01*
X418593Y-806672D01*
G01X356693Y-787172D02*
Y-779172D01*
X360493D01*
G01X359093Y-783039D02*
X356693D01*
G01X366593Y-779172D02*
X365793Y-779439D01*
X365193Y-780105D01*
X364793Y-780905D01*
X364493Y-781972D01*
X364393Y-783172D01*
X364493Y-784372D01*
X364793Y-785439D01*
X365193Y-786239D01*
X365793Y-786905D01*
X366593Y-787172D01*
X367393Y-786905D01*
X367993Y-786239D01*
X368393Y-785439D01*
X368693Y-784372D01*
X368793Y-783172D01*
X368693Y-781972D01*
X368393Y-780905D01*
X367993Y-780105D01*
X367393Y-779439D01*
X366593Y-779172D01*
G01X374593D02*
Y-787172D01*
G01X372293Y-779172D02*
X376893D01*
G01X379593Y-789839D02*
X385593D01*
G01X388593Y-787172D02*
Y-779172D01*
X390993D01*
X391793Y-779572D01*
X392393Y-780505D01*
X392593Y-781572D01*
X392393Y-782639D01*
X391893Y-783439D01*
X390993Y-783839D01*
X388593D01*
G01X396393Y-787172D02*
Y-779172D01*
X398393D01*
X399193Y-779572D01*
X399793Y-780105D01*
X400293Y-780905D01*
X400693Y-781839D01*
X400793Y-783172D01*
X400693Y-784505D01*
X400293Y-785439D01*
X399793Y-786239D01*
X399193Y-786772D01*
X398393Y-787172D01*
X396393D01*
G01X407393Y-782905D02*
X407793Y-782505D01*
X408093Y-781839D01*
X408293Y-780905D01*
X408093Y-780105D01*
X407693Y-779572D01*
X406993Y-779172D01*
X404293D01*
Y-787172D01*
X407593D01*
X408293Y-786639D01*
X408693Y-785839D01*
X408893Y-784905D01*
X408693Y-783972D01*
X408093Y-783172D01*
X407393Y-782905D01*
X404293D01*
G01X411593Y-789839D02*
X417593D01*
G01X424793Y-779839D02*
X424193Y-779439D01*
X423493Y-779172D01*
X422693D01*
X421793Y-779572D01*
X421093Y-780239D01*
X420593Y-781039D01*
X420193Y-782372D01*
X420093Y-783572D01*
X420293Y-784772D01*
X420593Y-785572D01*
X421193Y-786372D01*
X421893Y-786905D01*
X422593Y-787172D01*
X423293D01*
X423993Y-786905D01*
X424593Y-786505D01*
X425093Y-785972D01*
G01X430593Y-787172D02*
X429793Y-787039D01*
X429093Y-786505D01*
X428493Y-785705D01*
X428093Y-784772D01*
X427893Y-783705D01*
Y-782639D01*
X428093Y-781572D01*
X428493Y-780639D01*
X429093Y-779839D01*
X429793Y-779305D01*
X430593Y-779172D01*
X431393Y-779305D01*
X432093Y-779839D01*
X432693Y-780639D01*
X433093Y-781572D01*
X433293Y-782639D01*
Y-783705D01*
X433093Y-784772D01*
X432693Y-785705D01*
X432093Y-786505D01*
X431393Y-787039D01*
X430593Y-787172D01*
G01X436293D02*
Y-779172D01*
X440893Y-787172D01*
Y-779172D01*
G01X444093D02*
X446593Y-787172D01*
X449093Y-779172D01*
G01X456593Y-787172D02*
X452593D01*
Y-779172D01*
X456593D01*
G01X454993Y-783039D02*
X452593D01*
G01X460593Y-787172D02*
Y-779172D01*
X463093D01*
X463893Y-779572D01*
X464393Y-780105D01*
X464593Y-781172D01*
X464393Y-782239D01*
X463793Y-782905D01*
X463093Y-783305D01*
X460593D01*
G01X463093D02*
X464593Y-787172D01*
G01X470593Y-779172D02*
Y-787172D01*
G01X468293Y-779172D02*
X472893D01*
G01X480593Y-787172D02*
X476593D01*
Y-779172D01*
X480593D01*
G01X478993Y-783039D02*
X476593D01*
G01X484593Y-787172D02*
Y-779172D01*
X487093D01*
X487893Y-779572D01*
X488393Y-780105D01*
X488593Y-781172D01*
X488393Y-782239D01*
X487793Y-782905D01*
X487093Y-783305D01*
X484593D01*
G01X487093D02*
X488593Y-787172D01*
G01X333720Y71720D02*
Y65720D01*
G01D02*
X339720D01*
G01X361279Y71720D02*
Y65720D01*
G01D02*
X355279D01*
G01X335982Y84802D02*
X336729Y84177D01*
X337569Y83802D01*
X338315D01*
X339062Y84177D01*
X339622Y84802D01*
X339902Y85677D01*
X339715Y86552D01*
X339249Y87302D01*
X338409Y87802D01*
X337289Y88052D01*
X336635Y88552D01*
X336355Y89427D01*
X336542Y90302D01*
X337009Y90927D01*
X337662Y91302D01*
X338315D01*
X338969Y91052D01*
X339529Y90427D01*
G01X343762Y83552D02*
X347122Y91302D01*
G01X350795Y83802D02*
Y91302D01*
X355089Y83802D01*
Y91302D01*
G01X339720Y93279D02*
X333720D01*
G01D02*
Y87279D01*
G01X355279Y93279D02*
X361279D01*
G01D02*
Y87279D01*
G01X357235Y175935D02*
Y183435D01*
X359475D01*
X360222Y183060D01*
X360782Y182185D01*
X360969Y181185D01*
X360782Y180185D01*
X360315Y179435D01*
X359475Y179060D01*
X357235D01*
G01X364735Y175935D02*
Y183435D01*
X367069D01*
X367815Y183060D01*
X368282Y182560D01*
X368469Y181560D01*
X368282Y180560D01*
X367722Y179935D01*
X367069Y179560D01*
X364735D01*
G01X367069D02*
X368469Y175935D01*
G01X375969D02*
X372235D01*
Y183435D01*
X375969D01*
G01X374475Y179810D02*
X372235D01*
G01X379642Y176935D02*
X380389Y176310D01*
X381229Y175935D01*
X381975D01*
X382722Y176310D01*
X383282Y176935D01*
X383562Y177810D01*
X383375Y178685D01*
X382909Y179435D01*
X382069Y179935D01*
X380949Y180185D01*
X380295Y180685D01*
X380015Y181560D01*
X380202Y182435D01*
X380669Y183060D01*
X381322Y183435D01*
X381975D01*
X382629Y183185D01*
X383189Y182560D01*
G01X387142Y176935D02*
X387889Y176310D01*
X388729Y175935D01*
X389475D01*
X390222Y176310D01*
X390782Y176935D01*
X391062Y177810D01*
X390875Y178685D01*
X390409Y179435D01*
X389569Y179935D01*
X388449Y180185D01*
X387795Y180685D01*
X387515Y181560D01*
X387702Y182435D01*
X388169Y183060D01*
X388822Y183435D01*
X389475D01*
X390129Y183185D01*
X390689Y182560D01*
G01X395389Y178435D02*
X397815D01*
G01X402329Y175935D02*
Y183435D01*
X405875D01*
G01X404569Y179810D02*
X402329D01*
G01X410482Y183435D02*
X412722D01*
G01X411602D02*
Y175935D01*
G01X410482D02*
X412722D01*
G01X419102Y183435D02*
Y175935D01*
G01X416955Y183435D02*
X421249D01*
G01X360500Y207500D02*
Y201500D01*
X348500D01*
Y207500D01*
X360500D01*
G01Y199500D02*
Y193500D01*
X348500D01*
Y199500D01*
X360500D01*
G01X377700Y230158D02*
G03I-20700J-1D01*
G01D02*
X336300D01*
G01X351883Y252500D02*
Y255600D01*
X352803D01*
X353110Y255445D01*
X353340Y255083D01*
X353417Y254670D01*
X353340Y254257D01*
X353148Y253947D01*
X352803Y253792D01*
X351883D01*
G01X356593Y255342D02*
X356363Y255497D01*
X356095Y255600D01*
X355788D01*
X355443Y255445D01*
X355175Y255187D01*
X354983Y254877D01*
X354830Y254360D01*
X354792Y253895D01*
X354868Y253430D01*
X354983Y253120D01*
X355213Y252810D01*
X355482Y252603D01*
X355750Y252500D01*
X356018D01*
X356287Y252603D01*
X356517Y252758D01*
X356708Y252965D01*
G01X358198Y252862D02*
X358467Y252603D01*
X358773Y252500D01*
X359080Y252603D01*
X359348Y252913D01*
X359540Y253378D01*
X359617Y253843D01*
Y254412D01*
X359540Y254877D01*
X359348Y255290D01*
X359118Y255497D01*
X358850Y255600D01*
X358543Y255497D01*
X358313Y255290D01*
X358160Y254980D01*
X358083Y254567D01*
X358160Y254205D01*
X358352Y253843D01*
X358582Y253637D01*
X358850Y253585D01*
X359157Y253688D01*
X359387Y253947D01*
X359617Y254412D01*
G01X361222Y253792D02*
X361490Y254153D01*
X361720Y254360D01*
X362027Y254463D01*
X362295Y254360D01*
X362487Y254153D01*
X362640Y253843D01*
X362678Y253482D01*
X362640Y253172D01*
X362487Y252862D01*
X362257Y252603D01*
X361988Y252500D01*
X361682Y252603D01*
X361413Y252913D01*
X361260Y253378D01*
X361222Y253895D01*
X361298Y254567D01*
X361413Y254928D01*
X361605Y255290D01*
X361873Y255548D01*
X362142Y255600D01*
X362410Y255497D01*
X362602Y255238D01*
G01X332861Y559700D02*
Y518300D01*
G01X401562Y539000D02*
G03I-20701J0D01*
G01X387500Y68500D02*
G02X380700Y63500I-6035J1083D01*
G01X380800Y73700D02*
G02X387500Y68500I585J-6163D01*
G01X381800Y73700D02*
G03X375100Y68500I-585J-6163D01*
G01D02*
G03X381900Y63500I6035J1083D01*
G01X389310Y87500D02*
G03I-8010J0D01*
G01X376100Y93500D02*
X387100Y82000D01*
G01X368950Y77450D02*
X369050Y77650D01*
X369150Y77750D01*
X369300Y77850D01*
X369500Y77900D01*
X369750Y77850D01*
X370000Y77600D01*
X370050Y77450D01*
Y77100D01*
X370000Y76950D01*
X369900Y76800D01*
X369800Y76700D01*
X369650Y76600D01*
X369450Y76450D01*
X369300Y76250D01*
X369200Y76150D01*
X369100Y76000D01*
X369000Y75700D01*
X368950Y75350D01*
X370150D01*
G01X371100Y77050D02*
Y75350D01*
G01Y76550D02*
X371200Y76750D01*
X371300Y76900D01*
X371400Y77000D01*
X371600Y77050D01*
X371750D01*
X371950Y77000D01*
X372100Y76800D01*
X372200Y76600D01*
Y75350D01*
G01X374400Y77900D02*
Y75350D01*
G01X374560Y76100D02*
G03I-710J0D01*
G01X374400Y76550D02*
X374300Y76650D01*
X374150Y76750D01*
X374000Y76800D01*
X373750D01*
X373550Y76750D01*
X373400Y76650D01*
X373250Y76500D01*
X373200Y76400D01*
X373150Y76250D01*
Y76050D01*
X373200Y75800D01*
X373300Y75650D01*
X373400Y75550D01*
X373550Y75450D01*
X373700Y75400D01*
X373900D01*
X374150Y75450D01*
X374300Y75550D01*
X374400Y75650D01*
G01X376750Y77950D02*
Y75350D01*
G01X378250Y77050D02*
X378950Y75350D01*
X379650Y77050D01*
G01X381150Y77950D02*
Y75350D01*
G01X384050Y77100D02*
Y75350D01*
G01Y78350D02*
X383950Y78250D01*
Y78150D01*
X384050Y78050D01*
X384150Y78150D01*
Y78250D01*
X384050Y78350D01*
G01X385800Y76550D02*
X385900Y76750D01*
X386000Y76900D01*
X386100Y77000D01*
X386300Y77050D01*
X386450D01*
X386650Y77000D01*
X386800Y76800D01*
X386900Y76600D01*
Y75350D01*
G01X385800Y77050D02*
Y75350D01*
G01X388000Y77000D02*
X388900D01*
G01X388450Y77850D02*
Y75350D01*
X389150Y75400D01*
G01X391150Y76950D02*
X391000Y77000D01*
X390800Y77050D01*
X390650D01*
X390450Y77000D01*
X390350Y76950D01*
X390200Y76850D01*
X390100Y76750D01*
X390000Y76600D01*
X389950Y76500D01*
X389900Y76250D01*
Y76100D01*
X389950Y75900D01*
X390000Y75800D01*
X390100Y75650D01*
X390200Y75550D01*
X390350Y75450D01*
X390450Y75400D01*
X390700Y75350D01*
X390900D01*
X391150Y75450D01*
G01X382000Y207500D02*
Y201500D01*
X370000D01*
Y207500D01*
X382000D01*
G01Y200000D02*
Y194000D01*
X370000D01*
Y200000D01*
X382000D01*
G01X387500Y233200D02*
Y239800D01*
X400500D01*
Y233200D01*
X387500D01*
G01X390900Y244100D02*
X397100D01*
Y240900D01*
X390900D01*
Y244100D01*
G01Y248600D02*
X397100D01*
Y245400D01*
X390900D01*
Y248600D01*
G01X390219Y516200D02*
Y508800D01*
X372819D01*
Y516200D01*
X390219D01*
G01Y507200D02*
Y499800D01*
X372819D01*
Y507200D01*
X390219D01*
G01X380861Y559700D02*
Y518300D01*
G01X375383Y561500D02*
Y564600D01*
X376303D01*
X376610Y564445D01*
X376840Y564083D01*
X376917Y563670D01*
X376840Y563257D01*
X376648Y562947D01*
X376303Y562792D01*
X375383D01*
G01X380093Y564342D02*
X379863Y564497D01*
X379595Y564600D01*
X379288D01*
X378943Y564445D01*
X378675Y564187D01*
X378483Y563877D01*
X378330Y563360D01*
X378292Y562895D01*
X378368Y562430D01*
X378483Y562120D01*
X378713Y561810D01*
X378982Y561603D01*
X379250Y561500D01*
X379518D01*
X379787Y561603D01*
X380017Y561758D01*
X380208Y561965D01*
G01X382810Y561500D02*
Y564600D01*
X381392Y562378D01*
X383308D01*
G01X385910Y561500D02*
Y564600D01*
X384492Y562378D01*
X386408D01*
G01X392850Y77850D02*
Y75350D01*
X393550Y75400D01*
G01X392400Y77000D02*
X393300D01*
G01X425000Y207500D02*
Y201500D01*
X413000D01*
Y207500D01*
X425000D01*
G01Y200000D02*
Y194000D01*
X413000D01*
Y200000D01*
X425000D01*
G01X403500Y207500D02*
Y201500D01*
X391500D01*
Y207500D01*
X403500D01*
G01Y200000D02*
Y194000D01*
X391500D01*
Y200000D01*
X403500D01*
G01X449200Y230158D02*
G03I-20700J-1D01*
G01D02*
X407800D01*
G01X449562Y539000D02*
G03I-20700J0D01*
G01X425093Y-840172D02*
Y-832172D01*
X423893Y-833772D01*
G01Y-840172D02*
X426293D01*
G01X431193Y-836839D02*
X431893Y-835905D01*
X432493Y-835372D01*
X433293Y-835105D01*
X433993Y-835372D01*
X434493Y-835905D01*
X434893Y-836705D01*
X434993Y-837639D01*
X434893Y-838439D01*
X434493Y-839239D01*
X433893Y-839905D01*
X433193Y-840172D01*
X432393Y-839905D01*
X431693Y-839106D01*
X431293Y-837905D01*
X431193Y-836572D01*
X431393Y-834839D01*
X431693Y-833905D01*
X432193Y-832972D01*
X432893Y-832305D01*
X433593Y-832172D01*
X434293Y-832439D01*
X434793Y-833105D01*
G01X441093Y-840439D02*
X440893Y-840305D01*
Y-840039D01*
X441093Y-839905D01*
X441293Y-840039D01*
Y-840305D01*
X441093Y-840439D01*
G01X447193Y-836839D02*
X447893Y-835905D01*
X448493Y-835372D01*
X449293Y-835105D01*
X449993Y-835372D01*
X450493Y-835905D01*
X450893Y-836705D01*
X450993Y-837639D01*
X450893Y-838439D01*
X450493Y-839239D01*
X449893Y-839905D01*
X449193Y-840172D01*
X448393Y-839905D01*
X447693Y-839106D01*
X447293Y-837905D01*
X447193Y-836572D01*
X447393Y-834839D01*
X447693Y-833905D01*
X448193Y-832972D01*
X448893Y-832305D01*
X449593Y-832172D01*
X450293Y-832439D01*
X450793Y-833105D01*
G01X422883Y252500D02*
Y255600D01*
X423803D01*
X424110Y255445D01*
X424340Y255083D01*
X424417Y254670D01*
X424340Y254257D01*
X424148Y253947D01*
X423803Y253792D01*
X422883D01*
G01X427593Y255342D02*
X427363Y255497D01*
X427095Y255600D01*
X426788D01*
X426443Y255445D01*
X426175Y255187D01*
X425983Y254877D01*
X425830Y254360D01*
X425792Y253895D01*
X425868Y253430D01*
X425983Y253120D01*
X426213Y252810D01*
X426482Y252603D01*
X426750Y252500D01*
X427018D01*
X427287Y252603D01*
X427517Y252758D01*
X427708Y252965D01*
G01X429122Y253792D02*
X429390Y254153D01*
X429620Y254360D01*
X429927Y254463D01*
X430195Y254360D01*
X430387Y254153D01*
X430540Y253843D01*
X430578Y253482D01*
X430540Y253172D01*
X430387Y252862D01*
X430157Y252603D01*
X429888Y252500D01*
X429582Y252603D01*
X429313Y252913D01*
X429160Y253378D01*
X429122Y253895D01*
X429198Y254567D01*
X429313Y254928D01*
X429505Y255290D01*
X429773Y255548D01*
X430042Y255600D01*
X430310Y255497D01*
X430502Y255238D01*
G01X432950Y252500D02*
X433218Y252552D01*
X433525Y252707D01*
X433717Y252965D01*
X433793Y253327D01*
X433717Y253688D01*
X433487Y253998D01*
X433142Y254153D01*
X432758D01*
X432528Y254257D01*
X432337Y254515D01*
X432260Y254877D01*
X432375Y255238D01*
X432643Y255497D01*
X432950Y255600D01*
X433257Y255497D01*
X433525Y255238D01*
X433640Y254877D01*
X433563Y254515D01*
X433372Y254257D01*
X433142Y254153D01*
X432758D01*
X432413Y253998D01*
X432183Y253688D01*
X432107Y253327D01*
X432183Y252965D01*
X432375Y252707D01*
X432682Y252552D01*
X432950Y252500D01*
G01X438219Y507200D02*
Y499800D01*
X420819D01*
Y507200D01*
X438219D01*
G01Y516200D02*
Y508800D01*
X420819D01*
Y516200D01*
X438219D01*
G01X428861Y559700D02*
Y518300D01*
G01X423883Y561500D02*
Y564600D01*
X424803D01*
X425110Y564445D01*
X425340Y564083D01*
X425417Y563670D01*
X425340Y563257D01*
X425148Y562947D01*
X424803Y562792D01*
X423883D01*
G01X428593Y564342D02*
X428363Y564497D01*
X428095Y564600D01*
X427788D01*
X427443Y564445D01*
X427175Y564187D01*
X426983Y563877D01*
X426830Y563360D01*
X426792Y562895D01*
X426868Y562430D01*
X426983Y562120D01*
X427213Y561810D01*
X427482Y561603D01*
X427750Y561500D01*
X428018D01*
X428287Y561603D01*
X428517Y561758D01*
X428708Y561965D01*
G01X431310Y561500D02*
Y564600D01*
X429892Y562378D01*
X431808D01*
G01X433107Y562120D02*
X433337Y561758D01*
X433643Y561552D01*
X433988Y561500D01*
X434295Y561552D01*
X434602Y561810D01*
X434793Y562120D01*
X434832Y562430D01*
X434755Y562792D01*
X434487Y563050D01*
X434218Y563153D01*
X433873D01*
G01X434218D02*
X434448Y563308D01*
X434640Y563567D01*
X434717Y563877D01*
X434640Y564187D01*
X434448Y564445D01*
X434103Y564600D01*
X433758Y564548D01*
X433413Y564342D01*
G01X470093Y-840172D02*
Y-832172D01*
X468893Y-833772D01*
G01Y-840172D02*
X471293D01*
G01X477893D02*
X478093Y-838439D01*
X478393Y-836972D01*
X478793Y-835639D01*
X479293Y-834172D01*
X480093Y-832172D01*
X476093D01*
G01X486093Y-840439D02*
X485893Y-840305D01*
Y-840039D01*
X486093Y-839905D01*
X486293Y-840039D01*
Y-840305D01*
X486093Y-840439D01*
G01X492193Y-833505D02*
X492793Y-832705D01*
X493493Y-832305D01*
X494293Y-832172D01*
X495293Y-832439D01*
X495993Y-833105D01*
X496193Y-833905D01*
X496093Y-834706D01*
X495693Y-835372D01*
X493693Y-836705D01*
X492793Y-837639D01*
X492193Y-838972D01*
X491993Y-840172D01*
X496193D01*
G01X466845Y70500D02*
Y73600D01*
G01X468455D02*
Y70500D01*
G01Y72050D02*
X466845D01*
G01X471210Y70500D02*
Y73600D01*
X469792Y71378D01*
X471708D01*
G01X493200Y230158D02*
G03I-20700J-1D01*
G01D02*
X451800D01*
G01X466339Y492165D02*
Y262244D01*
X611221D01*
Y492165D01*
X466339D01*
G01X613189Y260275D02*
Y494133D01*
X464371D01*
Y260275D01*
X613189D01*
G01X467383Y252500D02*
Y255600D01*
X468303D01*
X468610Y255445D01*
X468840Y255083D01*
X468917Y254670D01*
X468840Y254257D01*
X468648Y253947D01*
X468303Y253792D01*
X467383D01*
G01X472093Y255342D02*
X471863Y255497D01*
X471595Y255600D01*
X471288D01*
X470943Y255445D01*
X470675Y255187D01*
X470483Y254877D01*
X470330Y254360D01*
X470292Y253895D01*
X470368Y253430D01*
X470483Y253120D01*
X470713Y252810D01*
X470982Y252603D01*
X471250Y252500D01*
X471518D01*
X471787Y252603D01*
X472017Y252758D01*
X472208Y252965D01*
G01X474273Y252500D02*
X474350Y253172D01*
X474465Y253740D01*
X474618Y254257D01*
X474810Y254825D01*
X475117Y255600D01*
X473583D01*
G01X477450D02*
X477143Y255497D01*
X476913Y255238D01*
X476760Y254928D01*
X476645Y254515D01*
X476607Y254050D01*
X476645Y253585D01*
X476760Y253172D01*
X476913Y252862D01*
X477143Y252603D01*
X477450Y252500D01*
X477757Y252603D01*
X477987Y252862D01*
X478140Y253172D01*
X478255Y253585D01*
X478293Y254050D01*
X478255Y254515D01*
X478140Y254928D01*
X477987Y255238D01*
X477757Y255497D01*
X477450Y255600D01*
G01X464584Y496004D02*
Y499104D01*
X465504D01*
X465811Y498949D01*
X466041Y498587D01*
X466118Y498174D01*
X466041Y497761D01*
X465849Y497451D01*
X465504Y497296D01*
X464584D01*
G01X467608Y499104D02*
Y496882D01*
X467761Y496417D01*
X468068Y496107D01*
X468451Y496004D01*
X468834Y496107D01*
X469141Y496417D01*
X469294Y496882D01*
Y499104D01*
G01X470823Y498587D02*
X471053Y498897D01*
X471321Y499052D01*
X471628Y499104D01*
X472011Y499001D01*
X472279Y498742D01*
X472356Y498432D01*
X472318Y498122D01*
X472164Y497864D01*
X471398Y497347D01*
X471053Y496986D01*
X470823Y496469D01*
X470746Y496004D01*
X472356D01*
G01X511043Y539000D02*
G03I-20700J0D01*
G01X490193Y-815172D02*
Y-807172D01*
X493993D01*
G01X492593Y-811039D02*
X490193D01*
G01X537200Y230158D02*
G03I-20700J-1D01*
G01D02*
X495800D01*
G01X499700Y516200D02*
Y508800D01*
X482300D01*
Y516200D01*
X499700D01*
G01Y507200D02*
Y499800D01*
X482300D01*
Y507200D01*
X499700D01*
G01X490342Y559700D02*
Y518300D01*
G01X484883Y562000D02*
Y565100D01*
X485803D01*
X486110Y564945D01*
X486340Y564583D01*
X486417Y564170D01*
X486340Y563757D01*
X486148Y563447D01*
X485803Y563292D01*
X484883D01*
G01X489593Y564842D02*
X489363Y564997D01*
X489095Y565100D01*
X488788D01*
X488443Y564945D01*
X488175Y564687D01*
X487983Y564377D01*
X487830Y563860D01*
X487792Y563395D01*
X487868Y562930D01*
X487983Y562620D01*
X488213Y562310D01*
X488482Y562103D01*
X488750Y562000D01*
X489018D01*
X489287Y562103D01*
X489517Y562258D01*
X489708Y562465D01*
G01X491850Y562000D02*
Y565100D01*
X491390Y564480D01*
G01Y562000D02*
X492310D01*
G01X494873D02*
X494950Y562672D01*
X495065Y563240D01*
X495218Y563757D01*
X495410Y564325D01*
X495717Y565100D01*
X494183D01*
G01X518324Y100552D02*
X519907Y95552D01*
X521490Y100552D01*
G01X523740Y95552D02*
Y100552D01*
X525260D01*
X525767Y100302D01*
X526147Y99719D01*
X526274Y99052D01*
X526147Y98385D01*
X525830Y97885D01*
X525260Y97635D01*
X523740D01*
G01X528714Y95552D02*
Y100552D01*
X529980D01*
X530487Y100302D01*
X530867Y99969D01*
X531184Y99469D01*
X531437Y98885D01*
X531500Y98052D01*
X531437Y97219D01*
X531184Y96635D01*
X530867Y96135D01*
X530487Y95802D01*
X529980Y95552D01*
X528714D01*
G01X535714Y98219D02*
X535967Y98469D01*
X536157Y98885D01*
X536284Y99469D01*
X536157Y99969D01*
X535904Y100302D01*
X535460Y100552D01*
X533750D01*
Y95552D01*
X535840D01*
X536284Y95885D01*
X536537Y96385D01*
X536664Y96969D01*
X536537Y97552D01*
X536157Y98052D01*
X535714Y98219D01*
X533750D01*
G01X544140Y96552D02*
X544457Y96052D01*
X544837Y95719D01*
X545280Y95552D01*
X545787Y95719D01*
X546167Y96052D01*
X546547Y96552D01*
X546674Y97219D01*
Y100552D01*
G01X549304Y99719D02*
X549684Y100219D01*
X550127Y100469D01*
X550634Y100552D01*
X551267Y100385D01*
X551710Y99969D01*
X551837Y99469D01*
X551774Y98969D01*
X551520Y98552D01*
X550254Y97719D01*
X549684Y97135D01*
X549304Y96302D01*
X549177Y95552D01*
X551837D01*
G01X510383Y252500D02*
Y255600D01*
X511303D01*
X511610Y255445D01*
X511840Y255083D01*
X511917Y254670D01*
X511840Y254257D01*
X511648Y253947D01*
X511303Y253792D01*
X510383D01*
G01X515093Y255342D02*
X514863Y255497D01*
X514595Y255600D01*
X514288D01*
X513943Y255445D01*
X513675Y255187D01*
X513483Y254877D01*
X513330Y254360D01*
X513292Y253895D01*
X513368Y253430D01*
X513483Y253120D01*
X513713Y252810D01*
X513982Y252603D01*
X514250Y252500D01*
X514518D01*
X514787Y252603D01*
X515017Y252758D01*
X515208Y252965D01*
G01X516622Y253792D02*
X516890Y254153D01*
X517120Y254360D01*
X517427Y254463D01*
X517695Y254360D01*
X517887Y254153D01*
X518040Y253843D01*
X518078Y253482D01*
X518040Y253172D01*
X517887Y252862D01*
X517657Y252603D01*
X517388Y252500D01*
X517082Y252603D01*
X516813Y252913D01*
X516660Y253378D01*
X516622Y253895D01*
X516698Y254567D01*
X516813Y254928D01*
X517005Y255290D01*
X517273Y255548D01*
X517542Y255600D01*
X517810Y255497D01*
X518002Y255238D01*
G01X519798Y252862D02*
X520067Y252603D01*
X520373Y252500D01*
X520680Y252603D01*
X520948Y252913D01*
X521140Y253378D01*
X521217Y253843D01*
Y254412D01*
X521140Y254877D01*
X520948Y255290D01*
X520718Y255497D01*
X520450Y255600D01*
X520143Y255497D01*
X519913Y255290D01*
X519760Y254980D01*
X519683Y254567D01*
X519760Y254205D01*
X519952Y253843D01*
X520182Y253637D01*
X520450Y253585D01*
X520757Y253688D01*
X520987Y253947D01*
X521217Y254412D01*
G01X547700Y507200D02*
Y499800D01*
X530300D01*
Y507200D01*
X547700D01*
G01Y516200D02*
Y508800D01*
X530300D01*
Y516200D01*
X547700D01*
G01X559043Y539000D02*
G03I-20701J0D01*
G01X538342Y559700D02*
Y518300D01*
G01X533383Y562000D02*
Y565100D01*
X534303D01*
X534610Y564945D01*
X534840Y564583D01*
X534917Y564170D01*
X534840Y563757D01*
X534648Y563447D01*
X534303Y563292D01*
X533383D01*
G01X538093Y564842D02*
X537863Y564997D01*
X537595Y565100D01*
X537288D01*
X536943Y564945D01*
X536675Y564687D01*
X536483Y564377D01*
X536330Y563860D01*
X536292Y563395D01*
X536368Y562930D01*
X536483Y562620D01*
X536713Y562310D01*
X536982Y562103D01*
X537250Y562000D01*
X537518D01*
X537787Y562103D01*
X538017Y562258D01*
X538208Y562465D01*
G01X540350Y562000D02*
Y565100D01*
X539890Y564480D01*
G01Y562000D02*
X540810D01*
G01X542722Y563292D02*
X542990Y563653D01*
X543220Y563860D01*
X543527Y563963D01*
X543795Y563860D01*
X543987Y563653D01*
X544140Y563343D01*
X544178Y562982D01*
X544140Y562672D01*
X543987Y562362D01*
X543757Y562103D01*
X543488Y562000D01*
X543182Y562103D01*
X542913Y562413D01*
X542760Y562878D01*
X542722Y563395D01*
X542798Y564067D01*
X542913Y564428D01*
X543105Y564790D01*
X543373Y565048D01*
X543642Y565100D01*
X543910Y564997D01*
X544102Y564738D01*
G01X546883Y188120D02*
X547075Y187810D01*
X547305Y187603D01*
X547573Y187500D01*
X547880Y187603D01*
X548110Y187810D01*
X548340Y188120D01*
X548417Y188533D01*
Y190600D01*
G01X550022Y190083D02*
X550252Y190393D01*
X550520Y190548D01*
X550827Y190600D01*
X551210Y190497D01*
X551478Y190238D01*
X551555Y189928D01*
X551517Y189618D01*
X551363Y189360D01*
X550597Y188843D01*
X550252Y188482D01*
X550022Y187965D01*
X549945Y187500D01*
X551555D01*
G01X599200Y230158D02*
G03I-20700J-1D01*
G01X541000Y234200D02*
Y240800D01*
X554000D01*
Y234200D01*
X541000D01*
G01X599200Y230158D02*
X557800D01*
G01X544400Y245100D02*
X550600D01*
Y241900D01*
X544400D01*
Y245100D01*
G01Y249600D02*
X550600D01*
Y246400D01*
X544400D01*
Y249600D01*
G01X607043Y539000D02*
G03I-20700J0D01*
G01X603500Y207000D02*
Y201000D01*
X591500D01*
Y207000D01*
X603500D01*
G01Y199500D02*
Y193500D01*
X591500D01*
Y199500D01*
X603500D01*
G01X573883Y253000D02*
Y256100D01*
X574803D01*
X575110Y255945D01*
X575340Y255583D01*
X575417Y255170D01*
X575340Y254757D01*
X575148Y254447D01*
X574803Y254292D01*
X573883D01*
G01X578593Y255842D02*
X578363Y255997D01*
X578095Y256100D01*
X577788D01*
X577443Y255945D01*
X577175Y255687D01*
X576983Y255377D01*
X576830Y254860D01*
X576792Y254395D01*
X576868Y253930D01*
X576983Y253620D01*
X577213Y253310D01*
X577482Y253103D01*
X577750Y253000D01*
X578018D01*
X578287Y253103D01*
X578517Y253258D01*
X578708Y253465D01*
G01X581310Y253000D02*
Y256100D01*
X579892Y253878D01*
X581808D01*
G01X583950Y256100D02*
X583643Y255997D01*
X583413Y255738D01*
X583260Y255428D01*
X583145Y255015D01*
X583107Y254550D01*
X583145Y254085D01*
X583260Y253672D01*
X583413Y253362D01*
X583643Y253103D01*
X583950Y253000D01*
X584257Y253103D01*
X584487Y253362D01*
X584640Y253672D01*
X584755Y254085D01*
X584793Y254550D01*
X584755Y255015D01*
X584640Y255428D01*
X584487Y255738D01*
X584257Y255997D01*
X583950Y256100D01*
G01X595700Y516200D02*
Y508800D01*
X578300D01*
Y516200D01*
X595700D01*
G01Y507200D02*
Y499800D01*
X578300D01*
Y507200D01*
X595700D01*
G01X586342Y559700D02*
Y518300D01*
G01X581883Y561500D02*
Y564600D01*
X582803D01*
X583110Y564445D01*
X583340Y564083D01*
X583417Y563670D01*
X583340Y563257D01*
X583148Y562947D01*
X582803Y562792D01*
X581883D01*
G01X586593Y564342D02*
X586363Y564497D01*
X586095Y564600D01*
X585788D01*
X585443Y564445D01*
X585175Y564187D01*
X584983Y563877D01*
X584830Y563360D01*
X584792Y562895D01*
X584868Y562430D01*
X584983Y562120D01*
X585213Y561810D01*
X585482Y561603D01*
X585750Y561500D01*
X586018D01*
X586287Y561603D01*
X586517Y561758D01*
X586708Y561965D01*
G01X588850Y561500D02*
Y564600D01*
X588390Y563980D01*
G01Y561500D02*
X589310D01*
G01X591107Y561965D02*
X591337Y561707D01*
X591605Y561552D01*
X591950Y561500D01*
X592295Y561603D01*
X592563Y561810D01*
X592755Y562172D01*
X592793Y562585D01*
X592717Y562998D01*
X592525Y563257D01*
X592257Y563463D01*
X591988Y563515D01*
X591720Y563463D01*
X591375Y563257D01*
X591490Y564600D01*
X592525D01*
G01X625000Y199500D02*
Y193500D01*
X613000D01*
Y199500D01*
X625000D01*
G01Y207000D02*
Y201000D01*
X613000D01*
Y207000D01*
X625000D01*
G01X643200Y230158D02*
G03I-20700J-1D01*
G01D02*
X601800D01*
G01X623820Y492165D02*
Y262244D01*
X768702D01*
Y492165D01*
X623820D01*
G01X770670Y260275D02*
Y494133D01*
X621852D01*
Y260275D01*
X770670D01*
G01X617383Y252500D02*
Y255600D01*
X618303D01*
X618610Y255445D01*
X618840Y255083D01*
X618917Y254670D01*
X618840Y254257D01*
X618648Y253947D01*
X618303Y253792D01*
X617383D01*
G01X622093Y255342D02*
X621863Y255497D01*
X621595Y255600D01*
X621288D01*
X620943Y255445D01*
X620675Y255187D01*
X620483Y254877D01*
X620330Y254360D01*
X620292Y253895D01*
X620368Y253430D01*
X620483Y253120D01*
X620713Y252810D01*
X620982Y252603D01*
X621250Y252500D01*
X621518D01*
X621787Y252603D01*
X622017Y252758D01*
X622208Y252965D01*
G01X624810Y252500D02*
Y255600D01*
X623392Y253378D01*
X625308D01*
G01X626722Y255083D02*
X626952Y255393D01*
X627220Y255548D01*
X627527Y255600D01*
X627910Y255497D01*
X628178Y255238D01*
X628255Y254928D01*
X628217Y254618D01*
X628063Y254360D01*
X627297Y253843D01*
X626952Y253482D01*
X626722Y252965D01*
X626645Y252500D01*
X628255D01*
G01X622065Y496004D02*
Y499104D01*
X622985D01*
X623292Y498949D01*
X623522Y498587D01*
X623599Y498174D01*
X623522Y497761D01*
X623330Y497451D01*
X622985Y497296D01*
X622065D01*
G01X625089Y499104D02*
Y496882D01*
X625242Y496417D01*
X625549Y496107D01*
X625932Y496004D01*
X626315Y496107D01*
X626622Y496417D01*
X626775Y496882D01*
Y499104D01*
G01X628304Y497296D02*
X628572Y497657D01*
X628802Y497864D01*
X629109Y497967D01*
X629377Y497864D01*
X629569Y497657D01*
X629722Y497347D01*
X629760Y496986D01*
X629722Y496676D01*
X629569Y496366D01*
X629339Y496107D01*
X629070Y496004D01*
X628764Y496107D01*
X628495Y496417D01*
X628342Y496882D01*
X628304Y497399D01*
X628380Y498071D01*
X628495Y498432D01*
X628687Y498794D01*
X628955Y499052D01*
X629224Y499104D01*
X629492Y499001D01*
X629684Y498742D01*
G01X668524Y539000D02*
G03I-20701J0D01*
G01X656617Y652000D02*
Y648900D01*
X655697D01*
X655390Y649055D01*
X655160Y649417D01*
X655083Y649830D01*
X655160Y650243D01*
X655352Y650553D01*
X655697Y650708D01*
X656617D01*
G01X653440Y652103D02*
X652060Y648900D01*
G01X650532Y652000D02*
Y648900D01*
X648768Y652000D01*
Y648900D01*
G01X646550Y652103D02*
X646627Y652052D01*
Y651948D01*
X646550Y651897D01*
X646473Y651948D01*
Y652052D01*
X646550Y652103D01*
G01Y650708D02*
X646627Y650657D01*
Y650553D01*
X646550Y650502D01*
X646473Y650553D01*
Y650657D01*
X646550Y650708D01*
G01X644293Y652000D02*
Y648900D01*
X643527D01*
X643220Y649055D01*
X642990Y649262D01*
X642798Y649572D01*
X642645Y649933D01*
X642607Y650450D01*
X642645Y650967D01*
X642798Y651328D01*
X642990Y651638D01*
X643220Y651845D01*
X643527Y652000D01*
X644293D01*
G01X641308D02*
X640350Y648900D01*
X639392Y652000D01*
G01X639737Y650915D02*
X640963D01*
G01X637250Y648900D02*
X637557Y649003D01*
X637787Y649262D01*
X637940Y649572D01*
X638055Y649985D01*
X638093Y650450D01*
X638055Y650915D01*
X637940Y651328D01*
X637787Y651638D01*
X637557Y651897D01*
X637250Y652000D01*
X636943Y651897D01*
X636713Y651638D01*
X636560Y651328D01*
X636445Y650915D01*
X636407Y650450D01*
X636445Y649985D01*
X636560Y649572D01*
X636713Y649262D01*
X636943Y649003D01*
X637250Y648900D01*
G01X634878Y652000D02*
Y648900D01*
X633422D01*
G01X633958Y650398D02*
X634878D01*
G01X631050Y648900D02*
X631357Y649003D01*
X631587Y649262D01*
X631740Y649572D01*
X631855Y649985D01*
X631893Y650450D01*
X631855Y650915D01*
X631740Y651328D01*
X631587Y651638D01*
X631357Y651897D01*
X631050Y652000D01*
X630743Y651897D01*
X630513Y651638D01*
X630360Y651328D01*
X630245Y650915D01*
X630207Y650450D01*
X630245Y649985D01*
X630360Y649572D01*
X630513Y649262D01*
X630743Y649003D01*
X631050Y648900D01*
G01X627950D02*
Y652000D01*
G01X628832Y648900D02*
X627068D01*
G01X625617Y652000D02*
Y648900D01*
X624697D01*
X624390Y649055D01*
X624160Y649417D01*
X624083Y649830D01*
X624160Y650243D01*
X624352Y650553D01*
X624697Y650708D01*
X625617D01*
G01X621443Y650347D02*
X621290Y650192D01*
X621175Y649933D01*
X621098Y649572D01*
X621175Y649262D01*
X621328Y649055D01*
X621597Y648900D01*
X622632D01*
Y652000D01*
X621367D01*
X621098Y651793D01*
X620945Y651483D01*
X620868Y651122D01*
X620945Y650760D01*
X621175Y650450D01*
X621443Y650347D01*
X622632D01*
G01X619608Y652000D02*
X618650Y648900D01*
X617692Y652000D01*
G01X618037Y650915D02*
X619263D01*
G01X616278Y652000D02*
Y648900D01*
X614822D01*
G01X615358Y650398D02*
X616278D01*
G01X612450Y648900D02*
X612757Y649003D01*
X612987Y649262D01*
X613140Y649572D01*
X613255Y649985D01*
X613293Y650450D01*
X613255Y650915D01*
X613140Y651328D01*
X612987Y651638D01*
X612757Y651897D01*
X612450Y652000D01*
X612143Y651897D01*
X611913Y651638D01*
X611760Y651328D01*
X611645Y650915D01*
X611607Y650450D01*
X611645Y649985D01*
X611760Y649572D01*
X611913Y649262D01*
X612143Y649003D01*
X612450Y648900D01*
G01X640900Y34600D02*
X647100D01*
Y31400D01*
X640900D01*
Y34600D01*
G01Y38600D02*
X647100D01*
Y35400D01*
X640900D01*
Y38600D01*
G01X650700Y55200D02*
X656700D01*
Y43200D01*
X650700D01*
Y55200D01*
G01X649200Y42900D02*
X639200D01*
G01Y47400D02*
Y47500D01*
X649200D01*
G01Y42900D02*
Y47500D01*
G01X639200Y42900D02*
Y47500D01*
G01X1002854Y174880D02*
Y93857D01*
X642264D01*
Y174880D01*
X1002854D01*
G01X654075Y141908D02*
Y105668D01*
X991043D01*
G01Y157008D02*
Y163069D01*
X654075D01*
Y156908D01*
G01X668000Y207000D02*
Y201000D01*
X656000D01*
Y207000D01*
X668000D01*
G01Y199500D02*
Y193500D01*
X656000D01*
Y199500D01*
X668000D01*
G01X646500Y207000D02*
Y201000D01*
X634500D01*
Y207000D01*
X646500D01*
G01Y199500D02*
Y193500D01*
X634500D01*
Y199500D01*
X646500D01*
G01X687200Y230158D02*
G03I-20700J-1D01*
G01D02*
X645800D01*
G01X657181Y516200D02*
Y508800D01*
X639781D01*
Y516200D01*
X657181D01*
G01Y507200D02*
Y499800D01*
X639781D01*
Y507200D01*
X657181D01*
G01X647823Y559700D02*
Y518300D01*
G01X641383Y562000D02*
Y565100D01*
X642303D01*
X642610Y564945D01*
X642840Y564583D01*
X642917Y564170D01*
X642840Y563757D01*
X642648Y563447D01*
X642303Y563292D01*
X641383D01*
G01X646093Y564842D02*
X645863Y564997D01*
X645595Y565100D01*
X645288D01*
X644943Y564945D01*
X644675Y564687D01*
X644483Y564377D01*
X644330Y563860D01*
X644292Y563395D01*
X644368Y562930D01*
X644483Y562620D01*
X644713Y562310D01*
X644982Y562103D01*
X645250Y562000D01*
X645518D01*
X645787Y562103D01*
X646017Y562258D01*
X646208Y562465D01*
G01X648350Y562000D02*
Y565100D01*
X647890Y564480D01*
G01Y562000D02*
X648810D01*
G01X651450D02*
Y565100D01*
X650990Y564480D01*
G01Y562000D02*
X651910D01*
G01X653707Y562465D02*
X653937Y562207D01*
X654205Y562052D01*
X654550Y562000D01*
X654895Y562103D01*
X655163Y562310D01*
X655355Y562672D01*
X655393Y563085D01*
X655317Y563498D01*
X655125Y563757D01*
X654857Y563963D01*
X654588Y564015D01*
X654320Y563963D01*
X653975Y563757D01*
X654090Y565100D01*
X655125D01*
G01X691600Y34900D02*
X685400D01*
Y38100D01*
X691600D01*
Y34900D01*
G01Y30900D02*
X685400D01*
Y34100D01*
X691600D01*
Y30900D01*
G01X674400Y55200D02*
X680400D01*
Y43200D01*
X674400D01*
Y55200D01*
G01X682300D02*
X688300D01*
Y43200D01*
X682300D01*
Y55200D01*
G01X666500D02*
X672500D01*
Y43200D01*
X666500D01*
Y55200D01*
G01X658600D02*
X664600D01*
Y43200D01*
X658600D01*
Y55200D01*
G01X689500Y207000D02*
Y201000D01*
X677500D01*
Y207000D01*
X689500D01*
G01Y199500D02*
Y193500D01*
X677500D01*
Y199500D01*
X689500D01*
G01X661883Y252500D02*
Y255600D01*
X662803D01*
X663110Y255445D01*
X663340Y255083D01*
X663417Y254670D01*
X663340Y254257D01*
X663148Y253947D01*
X662803Y253792D01*
X661883D01*
G01X666593Y255342D02*
X666363Y255497D01*
X666095Y255600D01*
X665788D01*
X665443Y255445D01*
X665175Y255187D01*
X664983Y254877D01*
X664830Y254360D01*
X664792Y253895D01*
X664868Y253430D01*
X664983Y253120D01*
X665213Y252810D01*
X665482Y252603D01*
X665750Y252500D01*
X666018D01*
X666287Y252603D01*
X666517Y252758D01*
X666708Y252965D01*
G01X669310Y252500D02*
Y255600D01*
X667892Y253378D01*
X669808D01*
G01X671950Y252500D02*
Y255600D01*
X671490Y254980D01*
G01Y252500D02*
X672410D01*
G01X716524Y539000D02*
G03I-20700J0D01*
G01X708400Y37400D02*
Y43600D01*
X711600D01*
Y37400D01*
X708400D01*
G01X699900Y33600D02*
X706100D01*
Y30400D01*
X699900D01*
Y33600D01*
G01X692900D02*
X699100D01*
Y30400D01*
X692900D01*
Y33600D01*
G01X692935Y38295D02*
X699135D01*
Y35095D01*
X692935D01*
Y38295D01*
G01X692900Y28600D02*
X699100D01*
Y25400D01*
X692900D01*
Y28600D01*
G01X699935Y38295D02*
X706135D01*
Y35095D01*
X699935D01*
Y38295D01*
G01X704134Y42363D02*
Y41198D01*
X701984D01*
G01X698016D02*
X695866D01*
Y42363D01*
G01X743870Y43900D02*
Y37811D01*
X715130D01*
Y43800D01*
G01X704400Y54900D02*
Y61100D01*
X707600D01*
Y54900D01*
X704400D01*
G01X711600Y51100D02*
Y44900D01*
X708400D01*
Y51100D01*
X711600D01*
G01X703200Y56200D02*
X697000D01*
Y59400D01*
X703200D01*
Y56200D01*
G01X694883Y61000D02*
Y64100D01*
X695803D01*
X696110Y63945D01*
X696340Y63583D01*
X696417Y63170D01*
X696340Y62757D01*
X696148Y62447D01*
X695803Y62292D01*
X694883D01*
G01X697907Y64100D02*
Y61878D01*
X698060Y61413D01*
X698367Y61103D01*
X698750Y61000D01*
X699133Y61103D01*
X699440Y61413D01*
X699593Y61878D01*
Y64100D01*
G01X701007Y61465D02*
X701237Y61207D01*
X701505Y61052D01*
X701850Y61000D01*
X702195Y61103D01*
X702463Y61310D01*
X702655Y61672D01*
X702693Y62085D01*
X702617Y62498D01*
X702425Y62757D01*
X702157Y62963D01*
X701888Y63015D01*
X701620Y62963D01*
X701275Y62757D01*
X701390Y64100D01*
X702425D01*
G01X704134Y53402D02*
Y52237D01*
G01X701984Y53402D02*
X704134D01*
G01X695866Y52237D02*
Y53402D01*
X698016D01*
G01X714883Y66000D02*
Y69100D01*
X715803D01*
X716110Y68945D01*
X716340Y68583D01*
X716417Y68170D01*
X716340Y67757D01*
X716148Y67447D01*
X715803Y67292D01*
X714883D01*
G01X717983Y69100D02*
Y66000D01*
X719517D01*
G01X721122Y68583D02*
X721352Y68893D01*
X721620Y69048D01*
X721927Y69100D01*
X722310Y68997D01*
X722578Y68738D01*
X722655Y68428D01*
X722617Y68118D01*
X722463Y67860D01*
X721697Y67343D01*
X721352Y66982D01*
X721122Y66465D01*
X721045Y66000D01*
X722655D01*
G01X715130Y58100D02*
Y64189D01*
G01X715100D02*
X743870D01*
Y58100D01*
G01X689800Y46200D02*
Y52400D01*
X693000D01*
Y46200D01*
X689800D01*
G01X710990Y207000D02*
Y201000D01*
X698990D01*
Y207000D01*
X710990D01*
G01Y199500D02*
Y193500D01*
X698990D01*
Y199500D01*
X710990D01*
G01X698481Y234200D02*
Y240800D01*
X711481D01*
Y234200D01*
X698481D01*
G01X756681Y230158D02*
G03I-20700J-1D01*
G01D02*
X715281D01*
G01X701881Y245100D02*
X708081D01*
Y241900D01*
X701881D01*
Y245100D01*
G01Y249600D02*
X708081D01*
Y246400D01*
X701881D01*
Y249600D01*
G01X705181Y516200D02*
Y508800D01*
X687781D01*
Y516200D01*
X705181D01*
G01Y507200D02*
Y499800D01*
X687781D01*
Y507200D01*
X705181D01*
G01X695823Y559700D02*
Y518300D01*
G01X689383Y562000D02*
Y565100D01*
X690303D01*
X690610Y564945D01*
X690840Y564583D01*
X690917Y564170D01*
X690840Y563757D01*
X690648Y563447D01*
X690303Y563292D01*
X689383D01*
G01X694093Y564842D02*
X693863Y564997D01*
X693595Y565100D01*
X693288D01*
X692943Y564945D01*
X692675Y564687D01*
X692483Y564377D01*
X692330Y563860D01*
X692292Y563395D01*
X692368Y562930D01*
X692483Y562620D01*
X692713Y562310D01*
X692982Y562103D01*
X693250Y562000D01*
X693518D01*
X693787Y562103D01*
X694017Y562258D01*
X694208Y562465D01*
G01X696350Y562000D02*
Y565100D01*
X695890Y564480D01*
G01Y562000D02*
X696810D01*
G01X699450D02*
Y565100D01*
X698990Y564480D01*
G01Y562000D02*
X699910D01*
G01X703010D02*
Y565100D01*
X701592Y562878D01*
X703508D01*
G01X732490Y207000D02*
Y201000D01*
X720490D01*
Y207000D01*
X732490D01*
G01Y199500D02*
Y193500D01*
X720490D01*
Y199500D01*
X732490D01*
G01X729383Y252500D02*
Y255600D01*
X730303D01*
X730610Y255445D01*
X730840Y255083D01*
X730917Y254670D01*
X730840Y254257D01*
X730648Y253947D01*
X730303Y253792D01*
X729383D01*
G01X734093Y255342D02*
X733863Y255497D01*
X733595Y255600D01*
X733288D01*
X732943Y255445D01*
X732675Y255187D01*
X732483Y254877D01*
X732330Y254360D01*
X732292Y253895D01*
X732368Y253430D01*
X732483Y253120D01*
X732713Y252810D01*
X732982Y252603D01*
X733250Y252500D01*
X733518D01*
X733787Y252603D01*
X734017Y252758D01*
X734208Y252965D01*
G01X736350Y252500D02*
Y255600D01*
X735890Y254980D01*
G01Y252500D02*
X736810D01*
G01X738607Y253120D02*
X738837Y252758D01*
X739143Y252552D01*
X739488Y252500D01*
X739795Y252552D01*
X740102Y252810D01*
X740293Y253120D01*
X740332Y253430D01*
X740255Y253792D01*
X739987Y254050D01*
X739718Y254153D01*
X739373D01*
G01X739718D02*
X739948Y254308D01*
X740140Y254567D01*
X740217Y254877D01*
X740140Y255187D01*
X739948Y255445D01*
X739603Y255600D01*
X739258Y255548D01*
X738913Y255342D01*
G01X741822Y253792D02*
X742090Y254153D01*
X742320Y254360D01*
X742627Y254463D01*
X742895Y254360D01*
X743087Y254153D01*
X743240Y253843D01*
X743278Y253482D01*
X743240Y253172D01*
X743087Y252862D01*
X742857Y252603D01*
X742588Y252500D01*
X742282Y252603D01*
X742013Y252913D01*
X741860Y253378D01*
X741822Y253895D01*
X741898Y254567D01*
X742013Y254928D01*
X742205Y255290D01*
X742473Y255548D01*
X742742Y255600D01*
X743010Y255497D01*
X743202Y255238D01*
G01X753181Y516200D02*
Y508800D01*
X735781D01*
Y516200D01*
X753181D01*
G01Y507200D02*
Y499800D01*
X735781D01*
Y507200D01*
X753181D01*
G01X764524Y539000D02*
G03I-20701J0D01*
G01X743823Y559700D02*
Y518300D01*
G01X736883Y561500D02*
Y564600D01*
X737803D01*
X738110Y564445D01*
X738340Y564083D01*
X738417Y563670D01*
X738340Y563257D01*
X738148Y562947D01*
X737803Y562792D01*
X736883D01*
G01X741593Y564342D02*
X741363Y564497D01*
X741095Y564600D01*
X740788D01*
X740443Y564445D01*
X740175Y564187D01*
X739983Y563877D01*
X739830Y563360D01*
X739792Y562895D01*
X739868Y562430D01*
X739983Y562120D01*
X740213Y561810D01*
X740482Y561603D01*
X740750Y561500D01*
X741018D01*
X741287Y561603D01*
X741517Y561758D01*
X741708Y561965D01*
G01X743850Y561500D02*
Y564600D01*
X743390Y563980D01*
G01Y561500D02*
X744310D01*
G01X746950D02*
Y564600D01*
X746490Y563980D01*
G01Y561500D02*
X747410D01*
G01X749207Y562120D02*
X749437Y561758D01*
X749743Y561552D01*
X750088Y561500D01*
X750395Y561552D01*
X750702Y561810D01*
X750893Y562120D01*
X750932Y562430D01*
X750855Y562792D01*
X750587Y563050D01*
X750318Y563153D01*
X749973D01*
G01X750318D02*
X750548Y563308D01*
X750740Y563567D01*
X750817Y563877D01*
X750740Y564187D01*
X750548Y564445D01*
X750203Y564600D01*
X749858Y564548D01*
X749513Y564342D01*
G01X772098Y620655D02*
Y594429D01*
X737522Y607542D01*
X772098Y620655D01*
G01X751400Y29100D02*
X757600D01*
Y25900D01*
X751400D01*
Y29100D01*
G01X760500Y46000D02*
Y40000D01*
X748500D01*
Y46000D01*
X760500D01*
G01Y37500D02*
Y31500D01*
X748500D01*
Y37500D01*
X760500D01*
G01X751400Y70100D02*
X757600D01*
Y66900D01*
X751400D01*
Y70100D01*
G01X760500Y63000D02*
Y57000D01*
X748500D01*
Y63000D01*
X760500D01*
G01Y54500D02*
Y48500D01*
X748500D01*
Y54500D01*
X760500D01*
G01X800681Y230158D02*
G03I-20700J-1D01*
G01D02*
X759281D01*
G01X772383Y253000D02*
Y256100D01*
X773303D01*
X773610Y255945D01*
X773840Y255583D01*
X773917Y255170D01*
X773840Y254757D01*
X773648Y254447D01*
X773303Y254292D01*
X772383D01*
G01X777093Y255842D02*
X776863Y255997D01*
X776595Y256100D01*
X776288D01*
X775943Y255945D01*
X775675Y255687D01*
X775483Y255377D01*
X775330Y254860D01*
X775292Y254395D01*
X775368Y253930D01*
X775483Y253620D01*
X775713Y253310D01*
X775982Y253103D01*
X776250Y253000D01*
X776518D01*
X776787Y253103D01*
X777017Y253258D01*
X777208Y253465D01*
G01X779350Y253000D02*
Y256100D01*
X778890Y255480D01*
G01Y253000D02*
X779810D01*
G01X781607Y253620D02*
X781837Y253258D01*
X782143Y253052D01*
X782488Y253000D01*
X782795Y253052D01*
X783102Y253310D01*
X783293Y253620D01*
X783332Y253930D01*
X783255Y254292D01*
X782987Y254550D01*
X782718Y254653D01*
X782373D01*
G01X782718D02*
X782948Y254808D01*
X783140Y255067D01*
X783217Y255377D01*
X783140Y255687D01*
X782948Y255945D01*
X782603Y256100D01*
X782258Y256048D01*
X781913Y255842D01*
G01X784707Y253465D02*
X784937Y253207D01*
X785205Y253052D01*
X785550Y253000D01*
X785895Y253103D01*
X786163Y253310D01*
X786355Y253672D01*
X786393Y254085D01*
X786317Y254498D01*
X786125Y254757D01*
X785857Y254963D01*
X785588Y255015D01*
X785320Y254963D01*
X784975Y254757D01*
X785090Y256100D01*
X786125D01*
G01X776821Y612883D02*
X777131Y613075D01*
X777338Y613305D01*
X777441Y613573D01*
X777338Y613880D01*
X777131Y614110D01*
X776821Y614340D01*
X776408Y614417D01*
X774341D01*
G01X777441Y616750D02*
X774341D01*
X774961Y616290D01*
G01X777441D02*
Y617210D01*
G01X774858Y619122D02*
X774548Y619352D01*
X774393Y619620D01*
X774341Y619927D01*
X774444Y620310D01*
X774703Y620578D01*
X775013Y620655D01*
X775323Y620617D01*
X775581Y620463D01*
X776098Y619697D01*
X776459Y619352D01*
X776976Y619122D01*
X777441Y619045D01*
Y620655D01*
G01X803933Y96500D02*
Y104000D01*
X806173D01*
X806920Y103625D01*
X807480Y102750D01*
X807667Y101750D01*
X807480Y100750D01*
X807013Y100000D01*
X806173Y99625D01*
X803933D01*
G01X811433Y96500D02*
Y104000D01*
X813767D01*
X814513Y103625D01*
X814980Y103125D01*
X815167Y102125D01*
X814980Y101125D01*
X814420Y100500D01*
X813767Y100125D01*
X811433D01*
G01X813767D02*
X815167Y96500D01*
G01X822667D02*
X818933D01*
Y104000D01*
X822667D01*
G01X821173Y100375D02*
X818933D01*
G01X826340Y97500D02*
X827087Y96875D01*
X827927Y96500D01*
X828673D01*
X829420Y96875D01*
X829980Y97500D01*
X830260Y98375D01*
X830073Y99250D01*
X829607Y100000D01*
X828767Y100500D01*
X827647Y100750D01*
X826993Y101250D01*
X826713Y102125D01*
X826900Y103000D01*
X827367Y103625D01*
X828020Y104000D01*
X828673D01*
X829327Y103750D01*
X829887Y103125D01*
G01X833840Y97500D02*
X834587Y96875D01*
X835427Y96500D01*
X836173D01*
X836920Y96875D01*
X837480Y97500D01*
X837760Y98375D01*
X837573Y99250D01*
X837107Y100000D01*
X836267Y100500D01*
X835147Y100750D01*
X834493Y101250D01*
X834213Y102125D01*
X834400Y103000D01*
X834867Y103625D01*
X835520Y104000D01*
X836173D01*
X836827Y103750D01*
X837387Y103125D01*
G01X842087Y99000D02*
X844513D01*
G01X849027Y96500D02*
Y104000D01*
X852573D01*
G01X851267Y100375D02*
X849027D01*
G01X857180Y104000D02*
X859420D01*
G01X858300D02*
Y96500D01*
G01X857180D02*
X859420D01*
G01X865800Y104000D02*
Y96500D01*
G01X863653Y104000D02*
X867947D01*
G01X844681Y230158D02*
G03I-20700J-1D01*
G01D02*
X803281D01*
G01X799500Y251807D02*
X796400D01*
Y252573D01*
X796555Y252880D01*
X796762Y253110D01*
X797072Y253302D01*
X797433Y253455D01*
X797950Y253493D01*
X798467Y253455D01*
X798828Y253302D01*
X799138Y253110D01*
X799345Y252880D01*
X799500Y252573D01*
Y251807D01*
G01X796917Y255022D02*
X796607Y255252D01*
X796452Y255520D01*
X796400Y255827D01*
X796503Y256210D01*
X796762Y256478D01*
X797072Y256555D01*
X797382Y256517D01*
X797640Y256363D01*
X798157Y255597D01*
X798518Y255252D01*
X799035Y255022D01*
X799500Y254945D01*
Y256555D01*
G01X799754Y266629D02*
Y259539D01*
X795954D01*
Y266629D01*
G01X799754Y267229D02*
Y260039D01*
X795954D01*
Y267229D01*
G01X799754Y267629D02*
Y260539D01*
X795954D01*
Y267679D01*
X799704D01*
G01X801900Y260400D02*
Y266600D01*
X805100D01*
Y260400D01*
X801900D01*
G01X790754Y260509D02*
Y266709D01*
X793954D01*
Y260509D01*
X790754D01*
G01X788954Y266709D02*
Y260509D01*
X785754D01*
Y266709D01*
X788954D01*
G01X780754Y260509D02*
Y266709D01*
X783954D01*
Y260509D01*
X780754D01*
G01X778507Y303000D02*
Y308000D01*
X779773D01*
X780280Y307750D01*
X780660Y307417D01*
X780977Y306917D01*
X781230Y306333D01*
X781293Y305500D01*
X781230Y304667D01*
X780977Y304083D01*
X780660Y303583D01*
X780280Y303250D01*
X779773Y303000D01*
X778507D01*
G01X785000D02*
Y308000D01*
X784240Y307000D01*
G01Y303000D02*
X785760D01*
G01X790100Y302833D02*
X789973Y302917D01*
Y303083D01*
X790100Y303167D01*
X790227Y303083D01*
Y302917D01*
X790100Y302833D01*
G01Y305083D02*
X789973Y305167D01*
Y305333D01*
X790100Y305417D01*
X790227Y305333D01*
Y305167D01*
X790100Y305083D01*
G01X793933Y303000D02*
Y308000D01*
X795453D01*
X795960Y307750D01*
X796340Y307167D01*
X796467Y306500D01*
X796340Y305833D01*
X796023Y305333D01*
X795453Y305083D01*
X793933D01*
G01X798907Y303750D02*
X799287Y303333D01*
X799730Y303083D01*
X800300Y303000D01*
X800870Y303167D01*
X801313Y303500D01*
X801630Y304083D01*
X801693Y304750D01*
X801567Y305417D01*
X801250Y305833D01*
X800807Y306167D01*
X800363Y306250D01*
X799920Y306167D01*
X799350Y305833D01*
X799540Y308000D01*
X801250D01*
G01X804197Y307167D02*
X804577Y307667D01*
X805020Y307917D01*
X805527Y308000D01*
X806160Y307833D01*
X806603Y307417D01*
X806730Y306917D01*
X806667Y306417D01*
X806413Y306000D01*
X805147Y305167D01*
X804577Y304583D01*
X804197Y303750D01*
X804070Y303000D01*
X806730D01*
G01X808917Y308000D02*
X810500Y303000D01*
X812083Y308000D01*
G01X813700Y301333D02*
X817500D01*
G01X819370Y303000D02*
Y308000D01*
G01X822030D02*
Y303000D01*
G01Y305500D02*
X819370D01*
G01X824470Y303667D02*
X824977Y303250D01*
X825547Y303000D01*
X826053D01*
X826560Y303250D01*
X826940Y303667D01*
X827130Y304250D01*
X827003Y304833D01*
X826687Y305333D01*
X826117Y305667D01*
X825357Y305833D01*
X824913Y306167D01*
X824723Y306750D01*
X824850Y307333D01*
X825167Y307750D01*
X825610Y308000D01*
X826053D01*
X826497Y307833D01*
X826877Y307417D01*
G01X778592Y295444D02*
Y300444D01*
X779858D01*
X780365Y300194D01*
X780745Y299861D01*
X781062Y299361D01*
X781315Y298777D01*
X781378Y297944D01*
X781315Y297111D01*
X781062Y296527D01*
X780745Y296027D01*
X780365Y295694D01*
X779858Y295444D01*
X778592D01*
G01X783882Y299611D02*
X784262Y300111D01*
X784705Y300361D01*
X785212Y300444D01*
X785845Y300277D01*
X786288Y299861D01*
X786415Y299361D01*
X786352Y298861D01*
X786098Y298444D01*
X784832Y297611D01*
X784262Y297027D01*
X783882Y296194D01*
X783755Y295444D01*
X786415D01*
G01X790185Y295277D02*
X790058Y295361D01*
Y295527D01*
X790185Y295611D01*
X790312Y295527D01*
Y295361D01*
X790185Y295277D01*
G01Y297527D02*
X790058Y297611D01*
Y297777D01*
X790185Y297861D01*
X790312Y297777D01*
Y297611D01*
X790185Y297527D01*
G01X794018Y295444D02*
Y300444D01*
X795538D01*
X796045Y300194D01*
X796425Y299611D01*
X796552Y298944D01*
X796425Y298277D01*
X796108Y297777D01*
X795538Y297527D01*
X794018D01*
G01X800385Y295444D02*
Y300444D01*
X799625Y299444D01*
G01Y295444D02*
X801145D01*
G01X804282Y299611D02*
X804662Y300111D01*
X805105Y300361D01*
X805612Y300444D01*
X806245Y300277D01*
X806688Y299861D01*
X806815Y299361D01*
X806752Y298861D01*
X806498Y298444D01*
X805232Y297611D01*
X804662Y297027D01*
X804282Y296194D01*
X804155Y295444D01*
X806815D01*
G01X809002Y300444D02*
X810585Y295444D01*
X812168Y300444D01*
G01X813785Y293777D02*
X817585D01*
G01X821292Y298111D02*
X821545Y298361D01*
X821735Y298777D01*
X821862Y299361D01*
X821735Y299861D01*
X821482Y300194D01*
X821038Y300444D01*
X819328D01*
Y295444D01*
X821418D01*
X821862Y295777D01*
X822115Y296277D01*
X822242Y296861D01*
X822115Y297444D01*
X821735Y297944D01*
X821292Y298111D01*
X819328D01*
G01X824618Y295444D02*
Y300444D01*
X826202D01*
X826708Y300194D01*
X827025Y299861D01*
X827152Y299194D01*
X827025Y298527D01*
X826645Y298111D01*
X826202Y297861D01*
X824618D01*
G01X826202D02*
X827152Y295444D01*
G01X830225Y300444D02*
X831745D01*
G01X830985D02*
Y295444D01*
G01X830225D02*
X831745D01*
G01X837478Y300027D02*
X837098Y300277D01*
X836655Y300444D01*
X836148D01*
X835578Y300194D01*
X835135Y299777D01*
X834818Y299277D01*
X834565Y298444D01*
X834502Y297694D01*
X834628Y296944D01*
X834818Y296444D01*
X835198Y295944D01*
X835642Y295611D01*
X836085Y295444D01*
X836528D01*
X836972Y295611D01*
X837352Y295861D01*
X837668Y296194D01*
G01X839792Y295444D02*
Y300444D01*
G01X842198D02*
X839792Y297361D01*
G01X842578Y295444D02*
X840868Y298777D01*
G01X778507Y288000D02*
Y293000D01*
X779773D01*
X780280Y292750D01*
X780660Y292417D01*
X780977Y291917D01*
X781230Y291333D01*
X781293Y290500D01*
X781230Y289667D01*
X780977Y289083D01*
X780660Y288583D01*
X780280Y288250D01*
X779773Y288000D01*
X778507D01*
G01X783607Y289000D02*
X783987Y288417D01*
X784493Y288083D01*
X785063Y288000D01*
X785570Y288083D01*
X786077Y288500D01*
X786393Y289000D01*
X786457Y289500D01*
X786330Y290083D01*
X785887Y290500D01*
X785443Y290667D01*
X784873D01*
G01X785443D02*
X785823Y290917D01*
X786140Y291333D01*
X786267Y291833D01*
X786140Y292333D01*
X785823Y292750D01*
X785253Y293000D01*
X784683Y292917D01*
X784113Y292583D01*
G01X790100Y287833D02*
X789973Y287917D01*
Y288083D01*
X790100Y288167D01*
X790227Y288083D01*
Y287917D01*
X790100Y287833D01*
G01Y290083D02*
X789973Y290167D01*
Y290333D01*
X790100Y290417D01*
X790227Y290333D01*
Y290167D01*
X790100Y290083D01*
G01X793933Y288000D02*
Y293000D01*
X795453D01*
X795960Y292750D01*
X796340Y292167D01*
X796467Y291500D01*
X796340Y290833D01*
X796023Y290333D01*
X795453Y290083D01*
X793933D01*
G01X798907Y289000D02*
X799287Y288417D01*
X799793Y288083D01*
X800363Y288000D01*
X800870Y288083D01*
X801377Y288500D01*
X801693Y289000D01*
X801757Y289500D01*
X801630Y290083D01*
X801187Y290500D01*
X800743Y290667D01*
X800173D01*
G01X800743D02*
X801123Y290917D01*
X801440Y291333D01*
X801567Y291833D01*
X801440Y292333D01*
X801123Y292750D01*
X800553Y293000D01*
X799983Y292917D01*
X799413Y292583D01*
G01X803817Y293000D02*
X805400Y288000D01*
X806983Y293000D01*
G01X809107Y289000D02*
X809487Y288417D01*
X809993Y288083D01*
X810563Y288000D01*
X811070Y288083D01*
X811577Y288500D01*
X811893Y289000D01*
X811957Y289500D01*
X811830Y290083D01*
X811387Y290500D01*
X810943Y290667D01*
X810373D01*
G01X810943D02*
X811323Y290917D01*
X811640Y291333D01*
X811767Y291833D01*
X811640Y292333D01*
X811323Y292750D01*
X810753Y293000D01*
X810183Y292917D01*
X809613Y292583D01*
G01X813700Y286333D02*
X817500D01*
G01X819117Y288000D02*
X820700Y293000D01*
X822283Y288000D01*
G01X821713Y289750D02*
X819687D01*
G01X824407Y293000D02*
Y289417D01*
X824660Y288667D01*
X825167Y288167D01*
X825800Y288000D01*
X826433Y288167D01*
X826940Y288667D01*
X827193Y289417D01*
Y293000D01*
G01X829570Y288000D02*
X832230Y293000D01*
G01X829570D02*
X832230Y288000D01*
G01X782217Y417731D02*
Y414631D01*
X783751D01*
G01X785241Y415096D02*
X785471Y414838D01*
X785739Y414683D01*
X786084Y414631D01*
X786429Y414734D01*
X786697Y414941D01*
X786889Y415303D01*
X786927Y415716D01*
X786851Y416129D01*
X786659Y416388D01*
X786391Y416594D01*
X786122Y416646D01*
X785854Y416594D01*
X785509Y416388D01*
X785624Y417731D01*
X786659D01*
G01X796915Y472823D02*
X781921D01*
Y418887D01*
G01D02*
X796915D01*
G01X811000Y252307D02*
X807900D01*
Y253073D01*
X808055Y253380D01*
X808262Y253610D01*
X808572Y253802D01*
X808933Y253955D01*
X809450Y253993D01*
X809967Y253955D01*
X810328Y253802D01*
X810638Y253610D01*
X810845Y253380D01*
X811000Y253073D01*
Y252307D01*
G01X810380Y255407D02*
X810742Y255637D01*
X810948Y255943D01*
X811000Y256288D01*
X810948Y256595D01*
X810690Y256902D01*
X810380Y257093D01*
X810070Y257132D01*
X809708Y257055D01*
X809450Y256787D01*
X809347Y256518D01*
Y256173D01*
G01Y256518D02*
X809192Y256748D01*
X808933Y256940D01*
X808623Y257017D01*
X808313Y256940D01*
X808055Y256748D01*
X807900Y256403D01*
X807952Y256058D01*
X808158Y255713D01*
G01X811400Y266520D02*
Y259430D01*
X807600D01*
Y266520D01*
G01X811400Y267120D02*
Y259930D01*
X807600D01*
Y267120D01*
G01X811400Y267520D02*
Y260430D01*
X807600D01*
Y267570D01*
X811350D01*
G01X817383Y253000D02*
Y256100D01*
X818303D01*
X818610Y255945D01*
X818840Y255583D01*
X818917Y255170D01*
X818840Y254757D01*
X818648Y254447D01*
X818303Y254292D01*
X817383D01*
G01X822093Y255842D02*
X821863Y255997D01*
X821595Y256100D01*
X821288D01*
X820943Y255945D01*
X820675Y255687D01*
X820483Y255377D01*
X820330Y254860D01*
X820292Y254395D01*
X820368Y253930D01*
X820483Y253620D01*
X820713Y253310D01*
X820982Y253103D01*
X821250Y253000D01*
X821518D01*
X821787Y253103D01*
X822017Y253258D01*
X822208Y253465D01*
G01X824350Y253000D02*
Y256100D01*
X823890Y255480D01*
G01Y253000D02*
X824810D01*
G01X826607Y253620D02*
X826837Y253258D01*
X827143Y253052D01*
X827488Y253000D01*
X827795Y253052D01*
X828102Y253310D01*
X828293Y253620D01*
X828332Y253930D01*
X828255Y254292D01*
X827987Y254550D01*
X827718Y254653D01*
X827373D01*
G01X827718D02*
X827948Y254808D01*
X828140Y255067D01*
X828217Y255377D01*
X828140Y255687D01*
X827948Y255945D01*
X827603Y256100D01*
X827258Y256048D01*
X826913Y255842D01*
G01X831010Y253000D02*
Y256100D01*
X829592Y253878D01*
X831508D01*
G01X817701Y341150D02*
X835299D01*
Y333850D01*
X817701D01*
Y341150D01*
G01X830147Y322080D02*
Y325180D01*
X830913D01*
X831220Y325025D01*
X831450Y324818D01*
X831642Y324508D01*
X831795Y324147D01*
X831833Y323630D01*
X831795Y323113D01*
X831642Y322752D01*
X831450Y322442D01*
X831220Y322235D01*
X830913Y322080D01*
X830147D01*
G01X834090D02*
Y325180D01*
X833630Y324560D01*
G01Y322080D02*
X834550D01*
G01X835020Y327100D02*
X827930D01*
Y330900D01*
X835020D01*
G01X835620Y327100D02*
X828430D01*
Y330900D01*
X835620D01*
G01X836020Y327100D02*
X828930D01*
Y330900D01*
X836070D01*
Y327150D01*
G01X835299Y364950D02*
X817701D01*
Y372250D01*
X835299D01*
Y364950D01*
G01X817701Y364250D02*
X835299D01*
Y356950D01*
X817701D01*
Y364250D01*
G01X835299Y341850D02*
X817701D01*
Y349150D01*
X835299D01*
Y341850D01*
G01X817715Y418887D02*
X832709D01*
Y472823D01*
X817715D01*
G01X857345Y70000D02*
Y73100D01*
G01X858955D02*
Y70000D01*
G01Y71550D02*
X857345D01*
G01X861250Y70000D02*
Y73100D01*
X860790Y72480D01*
G01Y70000D02*
X861710D01*
G01X864350D02*
X864618Y70052D01*
X864925Y70207D01*
X865117Y70465D01*
X865193Y70827D01*
X865117Y71188D01*
X864887Y71498D01*
X864542Y71653D01*
X864158D01*
X863928Y71757D01*
X863737Y72015D01*
X863660Y72377D01*
X863775Y72738D01*
X864043Y72997D01*
X864350Y73100D01*
X864657Y72997D01*
X864925Y72738D01*
X865040Y72377D01*
X864963Y72015D01*
X864772Y71757D01*
X864542Y71653D01*
X864158D01*
X863813Y71498D01*
X863583Y71188D01*
X863507Y70827D01*
X863583Y70465D01*
X863775Y70207D01*
X864082Y70052D01*
X864350Y70000D01*
G01X843650Y384799D02*
Y367201D01*
X836350D01*
Y384799D01*
X843650D01*
G01X852700Y367300D02*
X845300D01*
Y384700D01*
X852700D01*
Y367300D01*
G01X870700D02*
X863300D01*
Y384700D01*
X870700D01*
Y367300D01*
G01X861700D02*
X854300D01*
Y384700D01*
X861700D01*
Y367300D01*
G01X853517Y472823D02*
X838523D01*
Y418887D01*
G01D02*
X853517D01*
G01X855943Y502670D02*
Y487676D01*
X909879D01*
G01Y523470D02*
Y538464D01*
X855943D01*
Y523470D01*
G01X879700Y367300D02*
X872300D01*
Y384700D01*
X879700D01*
Y367300D01*
G01X898700D02*
X891300D01*
Y384700D01*
X898700D01*
Y367300D01*
G01X889200D02*
X881800D01*
Y384700D01*
X889200D01*
Y367300D01*
G01X885217Y417231D02*
Y414131D01*
X886751D01*
G01X889084D02*
Y417231D01*
X888624Y416611D01*
G01Y414131D02*
X889544D01*
G01X874317Y418887D02*
X889311D01*
Y472823D01*
X874317D01*
G01X873355Y571620D02*
Y574720D01*
G01X874965D02*
Y571620D01*
G01Y573170D02*
X873355D01*
G01X876532Y574203D02*
X876762Y574513D01*
X877030Y574668D01*
X877337Y574720D01*
X877720Y574617D01*
X877988Y574358D01*
X878065Y574048D01*
X878027Y573738D01*
X877873Y573480D01*
X877107Y572963D01*
X876762Y572602D01*
X876532Y572085D01*
X876455Y571620D01*
X878065D01*
G01X879517Y572240D02*
X879747Y571878D01*
X880053Y571672D01*
X880398Y571620D01*
X880705Y571672D01*
X881012Y571930D01*
X881203Y572240D01*
X881242Y572550D01*
X881165Y572912D01*
X880897Y573170D01*
X880628Y573273D01*
X880283D01*
G01X880628D02*
X880858Y573428D01*
X881050Y573687D01*
X881127Y573997D01*
X881050Y574307D01*
X880858Y574565D01*
X880513Y574720D01*
X880168Y574668D01*
X879823Y574462D01*
G01X886960Y558620D02*
G03I-9450J0D01*
G01X908200Y367300D02*
X900800D01*
Y384700D01*
X908200D01*
Y367300D01*
G01X917700D02*
X910300D01*
Y384700D01*
X917700D01*
Y367300D01*
G01X927200D02*
X919800D01*
Y384700D01*
X927200D01*
Y367300D01*
G01X905217Y485731D02*
Y482631D01*
X906751D01*
G01X908241Y483251D02*
X908471Y482889D01*
X908777Y482683D01*
X909122Y482631D01*
X909429Y482683D01*
X909736Y482941D01*
X909927Y483251D01*
X909966Y483561D01*
X909889Y483923D01*
X909621Y484181D01*
X909352Y484284D01*
X909007D01*
G01X909352D02*
X909582Y484439D01*
X909774Y484698D01*
X909851Y485008D01*
X909774Y485318D01*
X909582Y485576D01*
X909237Y485731D01*
X908892Y485679D01*
X908547Y485473D01*
G01X909879Y487676D02*
Y502670D01*
G01X941341Y251918D02*
Y255018D01*
G01X942951D02*
Y251918D01*
G01Y253468D02*
X941341D01*
G01X945246Y251918D02*
Y255018D01*
X944786Y254398D01*
G01Y251918D02*
X945706D01*
G01X948806D02*
Y255018D01*
X947388Y252796D01*
X949304D01*
G01X936700Y367300D02*
X929300D01*
Y384700D01*
X936700D01*
Y367300D01*
G01X946200D02*
X938800D01*
Y384700D01*
X946200D01*
Y367300D01*
G01X955700D02*
X948300D01*
Y384700D01*
X955700D01*
Y367300D01*
G01X973910Y16950D02*
G03I-9450J0D01*
G01X960305Y28950D02*
Y32050D01*
G01X961915D02*
Y28950D01*
G01Y30500D02*
X960305D01*
G01X963482Y31533D02*
X963712Y31843D01*
X963980Y31998D01*
X964287Y32050D01*
X964670Y31947D01*
X964938Y31688D01*
X965015Y31378D01*
X964977Y31068D01*
X964823Y30810D01*
X964057Y30293D01*
X963712Y29932D01*
X963482Y29415D01*
X963405Y28950D01*
X965015D01*
G01X966582Y31533D02*
X966812Y31843D01*
X967080Y31998D01*
X967387Y32050D01*
X967770Y31947D01*
X968038Y31688D01*
X968115Y31378D01*
X968077Y31068D01*
X967923Y30810D01*
X967157Y30293D01*
X966812Y29932D01*
X966582Y29415D01*
X966505Y28950D01*
X968115D01*
G01X970317Y90500D02*
X971900Y85500D01*
X973483Y90500D01*
G01X975733Y85500D02*
Y90500D01*
X977253D01*
X977760Y90250D01*
X978140Y89667D01*
X978267Y89000D01*
X978140Y88333D01*
X977823Y87833D01*
X977253Y87583D01*
X975733D01*
G01X980707Y85500D02*
Y90500D01*
X981973D01*
X982480Y90250D01*
X982860Y89917D01*
X983177Y89417D01*
X983430Y88833D01*
X983493Y88000D01*
X983430Y87167D01*
X983177Y86583D01*
X982860Y86083D01*
X982480Y85750D01*
X981973Y85500D01*
X980707D01*
G01X987707Y88167D02*
X987960Y88417D01*
X988150Y88833D01*
X988277Y89417D01*
X988150Y89917D01*
X987897Y90250D01*
X987453Y90500D01*
X985743D01*
Y85500D01*
X987833D01*
X988277Y85833D01*
X988530Y86333D01*
X988657Y86917D01*
X988530Y87500D01*
X988150Y88000D01*
X987707Y88167D01*
X985743D01*
G01X996133Y86500D02*
X996450Y86000D01*
X996830Y85667D01*
X997273Y85500D01*
X997780Y85667D01*
X998160Y86000D01*
X998540Y86500D01*
X998667Y87167D01*
Y90500D01*
G01X1002500Y85500D02*
Y90500D01*
X1001740Y89500D01*
G01Y85500D02*
X1003260D01*
G01X1015862Y92744D02*
X1006138D01*
Y123256D01*
X1015862D01*
Y92744D01*
G01X1009805Y127330D02*
X1009443Y127100D01*
X1009237Y126794D01*
X1009185Y126449D01*
X1009237Y126142D01*
X1009495Y125835D01*
X1009805Y125644D01*
X1010115Y125605D01*
X1010477Y125682D01*
X1010735Y125950D01*
X1010838Y126219D01*
Y126564D01*
G01Y126219D02*
X1010993Y125989D01*
X1011252Y125797D01*
X1011562Y125720D01*
X1011872Y125797D01*
X1012130Y125989D01*
X1012285Y126334D01*
X1012233Y126679D01*
X1012027Y127024D01*
G01X991043Y105668D02*
Y141808D01*
G01X997883Y178120D02*
X998075Y177810D01*
X998305Y177603D01*
X998573Y177500D01*
X998880Y177603D01*
X999110Y177810D01*
X999340Y178120D01*
X999417Y178533D01*
Y180600D01*
G01X1001750Y177500D02*
Y180600D01*
X1001290Y179980D01*
G01Y177500D02*
X1002210D01*
G01X985834Y565566D02*
Y568666D01*
G01X987444D02*
Y565566D01*
G01Y567116D02*
X985834D01*
G01X989011Y568149D02*
X989241Y568459D01*
X989509Y568614D01*
X989816Y568666D01*
X990199Y568563D01*
X990467Y568304D01*
X990544Y567994D01*
X990506Y567684D01*
X990352Y567426D01*
X989586Y566909D01*
X989241Y566548D01*
X989011Y566031D01*
X988934Y565566D01*
X990544D01*
G01X1017233Y88070D02*
X1017425Y87760D01*
X1017655Y87553D01*
X1017923Y87450D01*
X1018230Y87553D01*
X1018460Y87760D01*
X1018690Y88070D01*
X1018767Y88483D01*
Y90550D01*
G01X1020333Y87450D02*
Y90550D01*
X1021253D01*
X1021560Y90395D01*
X1021790Y90033D01*
X1021867Y89620D01*
X1021790Y89207D01*
X1021598Y88897D01*
X1021253Y88742D01*
X1020333D01*
G01X1023472Y90033D02*
X1023702Y90343D01*
X1023970Y90498D01*
X1024277Y90550D01*
X1024660Y90447D01*
X1024928Y90188D01*
X1025005Y89878D01*
X1024967Y89568D01*
X1024813Y89310D01*
X1024047Y88793D01*
X1023702Y88432D01*
X1023472Y87915D01*
X1023395Y87450D01*
X1025005D01*
G01X1024100Y96400D02*
X1017900D01*
Y99600D01*
X1024100D01*
Y96400D01*
G01X1026520Y115500D02*
Y120500D01*
G01X1029180D02*
Y115500D01*
G01Y118000D02*
X1026520D01*
G01X1031620Y116167D02*
X1032127Y115750D01*
X1032697Y115500D01*
X1033203D01*
X1033710Y115750D01*
X1034090Y116167D01*
X1034280Y116750D01*
X1034153Y117333D01*
X1033837Y117833D01*
X1033267Y118167D01*
X1032507Y118333D01*
X1032063Y118667D01*
X1031873Y119250D01*
X1032000Y119833D01*
X1032317Y120250D01*
X1032760Y120500D01*
X1033203D01*
X1033647Y120333D01*
X1034027Y119917D01*
G01X1039443Y120083D02*
X1039063Y120333D01*
X1038620Y120500D01*
X1038113D01*
X1037543Y120250D01*
X1037100Y119833D01*
X1036783Y119333D01*
X1036530Y118500D01*
X1036467Y117750D01*
X1036593Y117000D01*
X1036783Y116500D01*
X1037163Y116000D01*
X1037607Y115667D01*
X1038050Y115500D01*
X1038493D01*
X1038937Y115667D01*
X1039317Y115917D01*
X1039633Y116250D01*
G01X1046857Y115500D02*
Y120500D01*
X1048123D01*
X1048630Y120250D01*
X1049010Y119917D01*
X1049327Y119417D01*
X1049580Y118833D01*
X1049643Y118000D01*
X1049580Y117167D01*
X1049327Y116583D01*
X1049010Y116083D01*
X1048630Y115750D01*
X1048123Y115500D01*
X1046857D01*
G01X1054617D02*
X1052083D01*
Y120500D01*
X1054617D01*
G01X1053603Y118083D02*
X1052083D01*
G01X1058957Y118167D02*
X1059210Y118417D01*
X1059400Y118833D01*
X1059527Y119417D01*
X1059400Y119917D01*
X1059147Y120250D01*
X1058703Y120500D01*
X1056993D01*
Y115500D01*
X1059083D01*
X1059527Y115833D01*
X1059780Y116333D01*
X1059907Y116917D01*
X1059780Y117500D01*
X1059400Y118000D01*
X1058957Y118167D01*
X1056993D01*
G01X1062157Y120500D02*
Y116917D01*
X1062410Y116167D01*
X1062917Y115667D01*
X1063550Y115500D01*
X1064183Y115667D01*
X1064690Y116167D01*
X1064943Y116917D01*
Y120500D01*
G01X1069030Y118000D02*
X1070297D01*
Y116500D01*
X1069917Y116000D01*
X1069473Y115667D01*
X1068840Y115500D01*
X1068207Y115667D01*
X1067763Y116000D01*
X1067383Y116500D01*
X1067130Y117083D01*
X1067003Y117750D01*
Y118333D01*
X1067130Y118833D01*
X1067383Y119417D01*
X1067763Y119917D01*
X1068143Y120250D01*
X1068650Y120500D01*
X1069093D01*
X1069600Y120333D01*
X1069980Y120000D01*
G01X1077520Y115500D02*
Y120500D01*
G01X1080180D02*
Y115500D01*
G01Y118000D02*
X1077520D01*
G01X1085217Y115500D02*
X1082683D01*
Y120500D01*
X1085217D01*
G01X1084203Y118083D02*
X1082683D01*
G01X1087467Y115500D02*
X1089050Y120500D01*
X1090633Y115500D01*
G01X1090063Y117250D02*
X1088037D01*
G01X1092757Y115500D02*
Y120500D01*
X1094023D01*
X1094530Y120250D01*
X1094910Y119917D01*
X1095227Y119417D01*
X1095480Y118833D01*
X1095543Y118000D01*
X1095480Y117167D01*
X1095227Y116583D01*
X1094910Y116083D01*
X1094530Y115750D01*
X1094023Y115500D01*
X1092757D01*
G01X1100517D02*
X1097983D01*
Y120500D01*
X1100517D01*
G01X1099503Y118083D02*
X1097983D01*
G01X1103083Y115500D02*
Y120500D01*
X1104667D01*
X1105173Y120250D01*
X1105490Y119917D01*
X1105617Y119250D01*
X1105490Y118583D01*
X1105110Y118167D01*
X1104667Y117917D01*
X1103083D01*
G01X1104667D02*
X1105617Y115500D01*
G01X1028700Y128300D02*
X1021300D01*
Y145700D01*
X1028700D01*
Y128300D01*
G01X1047100Y124200D02*
X1036900D01*
Y128800D01*
X1047100D01*
Y124200D01*
G01X1024100Y116400D02*
X1017900D01*
Y119600D01*
X1024100D01*
Y116400D01*
G01X1045654Y129667D02*
X1039454D01*
Y132867D01*
X1045654D01*
Y129667D01*
G01Y137667D02*
X1039454D01*
Y140867D01*
X1045654D01*
Y137667D01*
G01X1039454Y144867D02*
X1045654D01*
Y141667D01*
X1039454D01*
Y144867D01*
G01X1045654Y133667D02*
X1039454D01*
Y136867D01*
X1045654D01*
Y133667D01*
G01X1034494Y148791D02*
X1028854D01*
G01X1026654D02*
X1024578D01*
Y150867D01*
G01X1018054Y185467D02*
Y192067D01*
X1031054D01*
Y185467D01*
X1018054D01*
G01X1039900Y184400D02*
Y190600D01*
X1043100D01*
Y184400D01*
X1039900D01*
G01X1017883Y178000D02*
Y181100D01*
X1018803D01*
X1019110Y180945D01*
X1019340Y180583D01*
X1019417Y180170D01*
X1019340Y179757D01*
X1019148Y179447D01*
X1018803Y179292D01*
X1017883D01*
G01X1020907Y181100D02*
Y178878D01*
X1021060Y178413D01*
X1021367Y178103D01*
X1021750Y178000D01*
X1022133Y178103D01*
X1022440Y178413D01*
X1022593Y178878D01*
Y181100D01*
G01X1024850Y178000D02*
Y181100D01*
X1024390Y180480D01*
G01Y178000D02*
X1025310D01*
G01X1024578Y162867D02*
Y168567D01*
G01Y174667D02*
Y176743D01*
X1026654D01*
G01X1028854D02*
X1034494D01*
G01X1037000Y195300D02*
X1043200D01*
Y192100D01*
X1037000D01*
Y195300D01*
G01X1018054Y195967D02*
Y202567D01*
X1031054D01*
Y195967D01*
X1018054D01*
G01X1072254Y124567D02*
X1064854D01*
Y141967D01*
X1072254D01*
Y124567D01*
G01X1052654Y129667D02*
X1046454D01*
Y132867D01*
X1052654D01*
Y129667D01*
G01X1049600Y140100D02*
Y133900D01*
X1046400D01*
Y140100D01*
X1049600D01*
G01X1052530Y150867D02*
Y148791D01*
X1050454D01*
G01X1077754Y162767D02*
X1080656Y165669D01*
Y171625D01*
X1068452D01*
Y153909D01*
X1080656D01*
Y159865D01*
X1077754Y162767D01*
G01X1068600Y190600D02*
Y184400D01*
X1065400D01*
Y190600D01*
X1068600D01*
G01X1055100D02*
Y184400D01*
X1051900D01*
Y190600D01*
X1055100D01*
G01X1059600D02*
Y184400D01*
X1056400D01*
Y190600D01*
X1059600D01*
G01X1064100D02*
Y184400D01*
X1060900D01*
Y190600D01*
X1064100D01*
G01X1050454Y176743D02*
X1052530D01*
G01D02*
Y174667D01*
G01X1066800Y278442D02*
Y268242D01*
X1062200D01*
Y278442D01*
X1066800D01*
G01Y325942D02*
Y315742D01*
X1062200D01*
Y325942D01*
X1066800D01*
G01X1062200Y357442D02*
Y367642D01*
X1066800D01*
Y357442D01*
X1062200D01*
G01X1066800Y420942D02*
Y410742D01*
X1062200D01*
Y420942D01*
X1066800D01*
G01Y468442D02*
Y458242D01*
X1062200D01*
Y468442D01*
X1066800D01*
G01Y515942D02*
Y505742D01*
X1062200D01*
Y515942D01*
X1066800D01*
G01X1062587Y546000D02*
X1065013D01*
G01X1070500Y557744D02*
Y533256D01*
G01X1071200Y557744D02*
Y533256D01*
G01X1071600Y557744D02*
Y533256D01*
G01X1070800Y557744D02*
Y533256D01*
G01X1072050D02*
X1069950D01*
G01X1070000Y545500D02*
Y533256D01*
G01Y557744D02*
X1072050D01*
G01X1070000D02*
Y545500D01*
G01X1073200Y92100D02*
Y98700D01*
X1086200D01*
Y92100D01*
X1073200D01*
G01X1093500Y79200D02*
Y85800D01*
X1106500D01*
Y79200D01*
X1093500D01*
G01X1089400Y92400D02*
Y98600D01*
X1092600D01*
Y92400D01*
X1089400D01*
G01X1093500D02*
Y98600D01*
X1096700D01*
Y92400D01*
X1093500D01*
G01X1105000Y94000D02*
X1107602Y91398D01*
X1111824D01*
Y103602D01*
X1098176D01*
Y91398D01*
X1102398D01*
X1105000Y94000D01*
G01X1093072Y129305D02*
X1086472D01*
Y142305D01*
X1093072D01*
Y129305D01*
G01X1084900Y104600D02*
X1091100D01*
Y101400D01*
X1084900D01*
Y104600D01*
G01X1095368Y162013D02*
X1101568D01*
Y158813D01*
X1095368D01*
Y162013D01*
G01X1095432Y144744D02*
X1101632D01*
Y141544D01*
X1095432D01*
Y144744D01*
G01X1095400Y149100D02*
X1101600D01*
Y145900D01*
X1095400D01*
Y149100D01*
G01X1095368Y157699D02*
X1101568D01*
Y154499D01*
X1095368D01*
Y157699D01*
G01Y153456D02*
X1101568D01*
Y150256D01*
X1095368D01*
Y153456D01*
G01X1103600Y166200D02*
X1093400D01*
Y170800D01*
X1103600D01*
Y166200D01*
G01X1101100Y186400D02*
X1094900D01*
Y189600D01*
X1101100D01*
Y186400D01*
G01X1097600Y171900D02*
X1091400D01*
Y175100D01*
X1097600D01*
Y171900D01*
G01X1101100Y177900D02*
X1094900D01*
Y181100D01*
X1101100D01*
Y177900D01*
G01X1098900Y175100D02*
X1105100D01*
Y171900D01*
X1098900D01*
Y175100D01*
G01X1101068Y181999D02*
X1094868D01*
Y185199D01*
X1101068D01*
Y181999D01*
G01X1081050Y174557D02*
X1083272D01*
X1083737Y174710D01*
X1084047Y175017D01*
X1084150Y175400D01*
X1084047Y175783D01*
X1083737Y176090D01*
X1083272Y176243D01*
X1081050D01*
G01X1081567Y177772D02*
X1081257Y178002D01*
X1081102Y178270D01*
X1081050Y178577D01*
X1081153Y178960D01*
X1081412Y179228D01*
X1081722Y179305D01*
X1082032Y179267D01*
X1082290Y179113D01*
X1082807Y178347D01*
X1083168Y178002D01*
X1083685Y177772D01*
X1084150Y177695D01*
Y179305D01*
G01X1083788Y180948D02*
X1084047Y181217D01*
X1084150Y181523D01*
X1084047Y181830D01*
X1083737Y182098D01*
X1083272Y182290D01*
X1082807Y182367D01*
X1082238D01*
X1081773Y182290D01*
X1081360Y182098D01*
X1081153Y181868D01*
X1081050Y181600D01*
X1081153Y181293D01*
X1081360Y181063D01*
X1081670Y180910D01*
X1082083Y180833D01*
X1082445Y180910D01*
X1082807Y181102D01*
X1083013Y181332D01*
X1083065Y181600D01*
X1082962Y181907D01*
X1082703Y182137D01*
X1082238Y182367D01*
G01X1088500Y196200D02*
Y202800D01*
X1101500D01*
Y196200D01*
X1088500D01*
G01X1073802Y247342D02*
Y240757D01*
X1124061D01*
G01X1073802Y267342D02*
Y253542D01*
G01X1124061Y280127D02*
X1073802D01*
Y273542D01*
G01Y314842D02*
Y301042D01*
G01Y294842D02*
Y288257D01*
X1124061D01*
G01X1073894Y282259D02*
Y285359D01*
X1074814D01*
X1075121Y285204D01*
X1075351Y284842D01*
X1075428Y284429D01*
X1075351Y284016D01*
X1075159Y283706D01*
X1074814Y283551D01*
X1073894D01*
G01X1077761Y282259D02*
X1077454Y282311D01*
X1077186Y282517D01*
X1076956Y282827D01*
X1076803Y283189D01*
X1076726Y283602D01*
Y284016D01*
X1076803Y284429D01*
X1076956Y284791D01*
X1077186Y285101D01*
X1077454Y285307D01*
X1077761Y285359D01*
X1078068Y285307D01*
X1078336Y285101D01*
X1078566Y284791D01*
X1078719Y284429D01*
X1078796Y284016D01*
Y283602D01*
X1078719Y283189D01*
X1078566Y282827D01*
X1078336Y282517D01*
X1078068Y282311D01*
X1077761Y282259D01*
G01X1078068Y283086D02*
X1078528Y282259D01*
G01X1080133Y283551D02*
X1080401Y283912D01*
X1080631Y284119D01*
X1080938Y284222D01*
X1081206Y284119D01*
X1081398Y283912D01*
X1081551Y283602D01*
X1081589Y283241D01*
X1081551Y282931D01*
X1081398Y282621D01*
X1081168Y282362D01*
X1080899Y282259D01*
X1080593Y282362D01*
X1080324Y282672D01*
X1080171Y283137D01*
X1080133Y283654D01*
X1080209Y284326D01*
X1080324Y284687D01*
X1080516Y285049D01*
X1080784Y285307D01*
X1081053Y285359D01*
X1081321Y285256D01*
X1081513Y284997D01*
G01X1073802Y342342D02*
Y335757D01*
X1124061D01*
G01X1073894Y329759D02*
Y332859D01*
X1074814D01*
X1075121Y332704D01*
X1075351Y332342D01*
X1075428Y331929D01*
X1075351Y331516D01*
X1075159Y331206D01*
X1074814Y331051D01*
X1073894D01*
G01X1077761Y329759D02*
X1077454Y329811D01*
X1077186Y330017D01*
X1076956Y330327D01*
X1076803Y330689D01*
X1076726Y331102D01*
Y331516D01*
X1076803Y331929D01*
X1076956Y332291D01*
X1077186Y332601D01*
X1077454Y332807D01*
X1077761Y332859D01*
X1078068Y332807D01*
X1078336Y332601D01*
X1078566Y332291D01*
X1078719Y331929D01*
X1078796Y331516D01*
Y331102D01*
X1078719Y330689D01*
X1078566Y330327D01*
X1078336Y330017D01*
X1078068Y329811D01*
X1077761Y329759D01*
G01X1078068Y330586D02*
X1078528Y329759D01*
G01X1080018Y330224D02*
X1080248Y329966D01*
X1080516Y329811D01*
X1080861Y329759D01*
X1081206Y329862D01*
X1081474Y330069D01*
X1081666Y330431D01*
X1081704Y330844D01*
X1081628Y331257D01*
X1081436Y331516D01*
X1081168Y331722D01*
X1080899Y331774D01*
X1080631Y331722D01*
X1080286Y331516D01*
X1080401Y332859D01*
X1081436D01*
G01X1124061Y327627D02*
X1073802D01*
Y321042D01*
G01Y362342D02*
Y348542D01*
G01Y409842D02*
Y396042D01*
G01Y389842D02*
Y383257D01*
X1124061D01*
G01X1073894Y377259D02*
Y380359D01*
X1074814D01*
X1075121Y380204D01*
X1075351Y379842D01*
X1075428Y379429D01*
X1075351Y379016D01*
X1075159Y378706D01*
X1074814Y378551D01*
X1073894D01*
G01X1077761Y377259D02*
X1077454Y377311D01*
X1077186Y377517D01*
X1076956Y377827D01*
X1076803Y378189D01*
X1076726Y378602D01*
Y379016D01*
X1076803Y379429D01*
X1076956Y379791D01*
X1077186Y380101D01*
X1077454Y380307D01*
X1077761Y380359D01*
X1078068Y380307D01*
X1078336Y380101D01*
X1078566Y379791D01*
X1078719Y379429D01*
X1078796Y379016D01*
Y378602D01*
X1078719Y378189D01*
X1078566Y377827D01*
X1078336Y377517D01*
X1078068Y377311D01*
X1077761Y377259D01*
G01X1078068Y378086D02*
X1078528Y377259D01*
G01X1081321D02*
Y380359D01*
X1079903Y378137D01*
X1081819D01*
G01X1124061Y375127D02*
X1073802D01*
Y368542D01*
G01X1073894Y424759D02*
Y427859D01*
X1074814D01*
X1075121Y427704D01*
X1075351Y427342D01*
X1075428Y426929D01*
X1075351Y426516D01*
X1075159Y426206D01*
X1074814Y426051D01*
X1073894D01*
G01X1077761Y424759D02*
X1077454Y424811D01*
X1077186Y425017D01*
X1076956Y425327D01*
X1076803Y425689D01*
X1076726Y426102D01*
Y426516D01*
X1076803Y426929D01*
X1076956Y427291D01*
X1077186Y427601D01*
X1077454Y427807D01*
X1077761Y427859D01*
X1078068Y427807D01*
X1078336Y427601D01*
X1078566Y427291D01*
X1078719Y426929D01*
X1078796Y426516D01*
Y426102D01*
X1078719Y425689D01*
X1078566Y425327D01*
X1078336Y425017D01*
X1078068Y424811D01*
X1077761Y424759D01*
G01X1078068Y425586D02*
X1078528Y424759D01*
G01X1080018Y425379D02*
X1080248Y425017D01*
X1080554Y424811D01*
X1080899Y424759D01*
X1081206Y424811D01*
X1081513Y425069D01*
X1081704Y425379D01*
X1081743Y425689D01*
X1081666Y426051D01*
X1081398Y426309D01*
X1081129Y426412D01*
X1080784D01*
G01X1081129D02*
X1081359Y426567D01*
X1081551Y426826D01*
X1081628Y427136D01*
X1081551Y427446D01*
X1081359Y427704D01*
X1081014Y427859D01*
X1080669Y427807D01*
X1080324Y427601D01*
G01X1124061Y422627D02*
X1073802D01*
Y416042D01*
G01Y457342D02*
Y443542D01*
G01Y437342D02*
Y430757D01*
X1124061D01*
G01X1073802Y484842D02*
Y478257D01*
X1124061D01*
G01X1073894Y472259D02*
Y475359D01*
X1074814D01*
X1075121Y475204D01*
X1075351Y474842D01*
X1075428Y474429D01*
X1075351Y474016D01*
X1075159Y473706D01*
X1074814Y473551D01*
X1073894D01*
G01X1077761Y472259D02*
X1077454Y472311D01*
X1077186Y472517D01*
X1076956Y472827D01*
X1076803Y473189D01*
X1076726Y473602D01*
Y474016D01*
X1076803Y474429D01*
X1076956Y474791D01*
X1077186Y475101D01*
X1077454Y475307D01*
X1077761Y475359D01*
X1078068Y475307D01*
X1078336Y475101D01*
X1078566Y474791D01*
X1078719Y474429D01*
X1078796Y474016D01*
Y473602D01*
X1078719Y473189D01*
X1078566Y472827D01*
X1078336Y472517D01*
X1078068Y472311D01*
X1077761Y472259D01*
G01X1078068Y473086D02*
X1078528Y472259D01*
G01X1080133Y474842D02*
X1080363Y475152D01*
X1080631Y475307D01*
X1080938Y475359D01*
X1081321Y475256D01*
X1081589Y474997D01*
X1081666Y474687D01*
X1081628Y474377D01*
X1081474Y474119D01*
X1080708Y473602D01*
X1080363Y473241D01*
X1080133Y472724D01*
X1080056Y472259D01*
X1081666D01*
G01X1124061Y470127D02*
X1073802D01*
Y463542D01*
G01Y504842D02*
Y491042D01*
G01X1124061Y517627D02*
X1073802D01*
Y511042D01*
G01X1073883Y519000D02*
Y522100D01*
X1074803D01*
X1075110Y521945D01*
X1075340Y521583D01*
X1075417Y521170D01*
X1075340Y520757D01*
X1075148Y520447D01*
X1074803Y520292D01*
X1073883D01*
G01X1077750Y519000D02*
X1077443Y519052D01*
X1077175Y519258D01*
X1076945Y519568D01*
X1076792Y519930D01*
X1076715Y520343D01*
Y520757D01*
X1076792Y521170D01*
X1076945Y521532D01*
X1077175Y521842D01*
X1077443Y522048D01*
X1077750Y522100D01*
X1078057Y522048D01*
X1078325Y521842D01*
X1078555Y521532D01*
X1078708Y521170D01*
X1078785Y520757D01*
Y520343D01*
X1078708Y519930D01*
X1078555Y519568D01*
X1078325Y519258D01*
X1078057Y519052D01*
X1077750Y519000D01*
G01X1078057Y519827D02*
X1078517Y519000D01*
G01X1080850D02*
Y522100D01*
X1080390Y521480D01*
G01Y519000D02*
X1081310D01*
G01X1086500Y545500D02*
X1095000Y541500D01*
Y549500D01*
X1087000Y545500D01*
G01X1110000D02*
Y533256D01*
X1072000D01*
Y545500D01*
G01X1086500Y551000D02*
Y540000D01*
G01X1072000Y545500D02*
Y557744D01*
G01D02*
X1110000D01*
Y545500D01*
G01X1095300D02*
X1097700D01*
G01X1086500D02*
X1083900D01*
G01X1077233Y622574D02*
Y648800D01*
X1111809Y635687D01*
X1077233Y622574D01*
G01X1074821Y640883D02*
X1075131Y641075D01*
X1075338Y641305D01*
X1075441Y641573D01*
X1075338Y641880D01*
X1075131Y642110D01*
X1074821Y642340D01*
X1074408Y642417D01*
X1072341D01*
G01X1075441Y644750D02*
X1072341D01*
X1072961Y644290D01*
G01X1075441D02*
Y645210D01*
G01X1072341Y647850D02*
X1072444Y647543D01*
X1072703Y647313D01*
X1073013Y647160D01*
X1073426Y647045D01*
X1073891Y647007D01*
X1074356Y647045D01*
X1074769Y647160D01*
X1075079Y647313D01*
X1075338Y647543D01*
X1075441Y647850D01*
X1075338Y648157D01*
X1075079Y648387D01*
X1074769Y648540D01*
X1074356Y648655D01*
X1073891Y648693D01*
X1073426Y648655D01*
X1073013Y648540D01*
X1072703Y648387D01*
X1072444Y648157D01*
X1072341Y647850D01*
G01X1107900Y85300D02*
X1118100D01*
Y80700D01*
X1107900D01*
Y85300D01*
G01X1108400Y89600D02*
X1114600D01*
Y86400D01*
X1108400D01*
Y89600D01*
G01X1136241Y121756D02*
X1129641D01*
Y134756D01*
X1136241D01*
Y121756D01*
G01X1126741D02*
X1120141D01*
Y134756D01*
X1126741D01*
Y121756D01*
G01X1104057Y108050D02*
Y105828D01*
X1104210Y105363D01*
X1104517Y105053D01*
X1104900Y104950D01*
X1105283Y105053D01*
X1105590Y105363D01*
X1105743Y105828D01*
Y108050D01*
G01X1108000Y104950D02*
Y108050D01*
X1107540Y107430D01*
G01Y104950D02*
X1108460D01*
G01X1110448Y105312D02*
X1110717Y105053D01*
X1111023Y104950D01*
X1111330Y105053D01*
X1111598Y105363D01*
X1111790Y105828D01*
X1111867Y106293D01*
Y106862D01*
X1111790Y107327D01*
X1111598Y107740D01*
X1111368Y107947D01*
X1111100Y108050D01*
X1110793Y107947D01*
X1110563Y107740D01*
X1110410Y107430D01*
X1110333Y107017D01*
X1110410Y106655D01*
X1110602Y106293D01*
X1110832Y106087D01*
X1111100Y106035D01*
X1111407Y106138D01*
X1111637Y106397D01*
X1111867Y106862D01*
G01X1106100Y143600D02*
Y137400D01*
X1102900D01*
Y143600D01*
X1106100D01*
G01X1114100D02*
Y137400D01*
X1110900D01*
Y143600D01*
X1114100D01*
G01X1127600Y136857D02*
X1121400D01*
Y140057D01*
X1127600D01*
Y136857D01*
G01X1106900Y137400D02*
Y143600D01*
X1110100D01*
Y137400D01*
X1106900D01*
G01X1128600Y140057D02*
X1134800D01*
Y136857D01*
X1128600D01*
Y140057D01*
G01X1125068Y144156D02*
X1131268D01*
Y140956D01*
X1125068D01*
Y144156D01*
G01X1116123Y154799D02*
Y152723D01*
G01D02*
X1118268D01*
G01X1110883Y182000D02*
Y185100D01*
X1111803D01*
X1112110Y184945D01*
X1112340Y184583D01*
X1112417Y184170D01*
X1112340Y183757D01*
X1112148Y183447D01*
X1111803Y183292D01*
X1110883D01*
G01X1113907Y185100D02*
Y182878D01*
X1114060Y182413D01*
X1114367Y182103D01*
X1114750Y182000D01*
X1115133Y182103D01*
X1115440Y182413D01*
X1115593Y182878D01*
Y185100D01*
G01X1117773Y182000D02*
X1117850Y182672D01*
X1117965Y183240D01*
X1118118Y183757D01*
X1118310Y184325D01*
X1118617Y185100D01*
X1117083D01*
G01X1118268Y180675D02*
X1116123D01*
Y178599D01*
G01X1108400Y190900D02*
Y197100D01*
X1111600D01*
Y190900D01*
X1108400D01*
G01X1116400D02*
Y197100D01*
X1119600D01*
Y190900D01*
X1116400D01*
G01X1104400D02*
Y197100D01*
X1107600D01*
Y190900D01*
X1104400D01*
G01X1112400D02*
Y197100D01*
X1115600D01*
Y190900D01*
X1112400D01*
G01X1124393Y194356D02*
X1130593D01*
Y191156D01*
X1124393D01*
Y194356D01*
G01X1120400Y190900D02*
Y197100D01*
X1123600D01*
Y190900D01*
X1120400D01*
G01X1118851Y235560D02*
Y238660D01*
X1119771D01*
X1120078Y238505D01*
X1120308Y238143D01*
X1120385Y237730D01*
X1120308Y237317D01*
X1120116Y237007D01*
X1119771Y236852D01*
X1118851D01*
G01X1122718Y235560D02*
X1122411Y235612D01*
X1122143Y235818D01*
X1121913Y236128D01*
X1121760Y236490D01*
X1121683Y236903D01*
Y237317D01*
X1121760Y237730D01*
X1121913Y238092D01*
X1122143Y238402D01*
X1122411Y238608D01*
X1122718Y238660D01*
X1123025Y238608D01*
X1123293Y238402D01*
X1123523Y238092D01*
X1123676Y237730D01*
X1123753Y237317D01*
Y236903D01*
X1123676Y236490D01*
X1123523Y236128D01*
X1123293Y235818D01*
X1123025Y235612D01*
X1122718Y235560D01*
G01X1123025Y236387D02*
X1123485Y235560D01*
G01X1125818D02*
Y238660D01*
X1125358Y238040D01*
G01Y235560D02*
X1126278D01*
G01X1128075Y236025D02*
X1128305Y235767D01*
X1128573Y235612D01*
X1128918Y235560D01*
X1129263Y235663D01*
X1129531Y235870D01*
X1129723Y236232D01*
X1129761Y236645D01*
X1129685Y237058D01*
X1129493Y237317D01*
X1129225Y237523D01*
X1128956Y237575D01*
X1128688Y237523D01*
X1128343Y237317D01*
X1128458Y238660D01*
X1129493D01*
G01X1133468Y234560D02*
Y221560D01*
X1118468D01*
Y234560D01*
X1133468D01*
G01X1113265Y222641D02*
X1107065D01*
Y225841D01*
X1113265D01*
Y222641D01*
G01X1116415D02*
X1110215D01*
Y225841D01*
X1116415D01*
Y222641D01*
G01X1116331Y230141D02*
X1110131D01*
Y233341D01*
X1116331D01*
Y230141D01*
G01X1106981Y233341D02*
X1113181D01*
Y230141D01*
X1106981D01*
Y233341D01*
G01X1119273Y546500D02*
X1121513D01*
G01X1120300Y548125D02*
Y544875D01*
G01X1102883Y528500D02*
Y531600D01*
X1103803D01*
X1104110Y531445D01*
X1104340Y531083D01*
X1104417Y530670D01*
X1104340Y530257D01*
X1104148Y529947D01*
X1103803Y529792D01*
X1102883D01*
G01X1105907Y528500D02*
Y531600D01*
X1106673D01*
X1106980Y531445D01*
X1107210Y531238D01*
X1107402Y530928D01*
X1107555Y530567D01*
X1107593Y530050D01*
X1107555Y529533D01*
X1107402Y529172D01*
X1107210Y528862D01*
X1106980Y528655D01*
X1106673Y528500D01*
X1105907D01*
G01X1109850D02*
X1110118Y528552D01*
X1110425Y528707D01*
X1110617Y528965D01*
X1110693Y529327D01*
X1110617Y529688D01*
X1110387Y529998D01*
X1110042Y530153D01*
X1109658D01*
X1109428Y530257D01*
X1109237Y530515D01*
X1109160Y530877D01*
X1109275Y531238D01*
X1109543Y531497D01*
X1109850Y531600D01*
X1110157Y531497D01*
X1110425Y531238D01*
X1110540Y530877D01*
X1110463Y530515D01*
X1110272Y530257D01*
X1110042Y530153D01*
X1109658D01*
X1109313Y529998D01*
X1109083Y529688D01*
X1109007Y529327D01*
X1109083Y528965D01*
X1109275Y528707D01*
X1109582Y528552D01*
X1109850Y528500D01*
G01X1146383Y98020D02*
X1146575Y97710D01*
X1146805Y97503D01*
X1147073Y97400D01*
X1147380Y97503D01*
X1147610Y97710D01*
X1147840Y98020D01*
X1147917Y98433D01*
Y100500D01*
G01X1149483Y97400D02*
Y100500D01*
X1150403D01*
X1150710Y100345D01*
X1150940Y99983D01*
X1151017Y99570D01*
X1150940Y99157D01*
X1150748Y98847D01*
X1150403Y98692D01*
X1149483D01*
G01X1152507Y98020D02*
X1152737Y97658D01*
X1153043Y97452D01*
X1153388Y97400D01*
X1153695Y97452D01*
X1154002Y97710D01*
X1154193Y98020D01*
X1154232Y98330D01*
X1154155Y98692D01*
X1153887Y98950D01*
X1153618Y99053D01*
X1153273D01*
G01X1153618D02*
X1153848Y99208D01*
X1154040Y99467D01*
X1154117Y99777D01*
X1154040Y100087D01*
X1153848Y100345D01*
X1153503Y100500D01*
X1153158Y100448D01*
X1152813Y100242D01*
G01X1145744Y85538D02*
Y95262D01*
X1176256D01*
Y85538D01*
X1145744D01*
G01X1155887Y128918D02*
X1149287D01*
Y141918D01*
X1155887D01*
Y128918D01*
G01X1140383Y127500D02*
Y130600D01*
X1141303D01*
X1141610Y130445D01*
X1141840Y130083D01*
X1141917Y129670D01*
X1141840Y129257D01*
X1141648Y128947D01*
X1141303Y128792D01*
X1140383D01*
G01X1143483Y128120D02*
X1143675Y127810D01*
X1143905Y127603D01*
X1144173Y127500D01*
X1144480Y127603D01*
X1144710Y127810D01*
X1144940Y128120D01*
X1145017Y128533D01*
Y130600D01*
G01X1147350Y127500D02*
Y130600D01*
X1146890Y129980D01*
G01Y127500D02*
X1147810D01*
G01X1142085Y142913D02*
Y148913D01*
X1154085D01*
Y142913D01*
X1142085D01*
G01X1164900Y157300D02*
X1157500D01*
Y174700D01*
X1164900D01*
Y157300D01*
G01X1145868Y152723D02*
X1148013D01*
Y154799D01*
G01X1132168Y152723D02*
X1135968D01*
G01Y180675D02*
X1132168D01*
G01X1148013Y178599D02*
Y180675D01*
X1145868D01*
G01X1158650Y208299D02*
Y190701D01*
X1151350D01*
Y208299D01*
X1158650D01*
G01X1131400Y190900D02*
Y197100D01*
X1134600D01*
Y190900D01*
X1131400D01*
G01X1144341Y190899D02*
X1136941D01*
Y208299D01*
X1144341D01*
Y190899D01*
G01X1133961Y240757D02*
X1134038D01*
G01D02*
Y280127D01*
X1133961D01*
G01Y288257D02*
X1134038D01*
G01D02*
Y327627D01*
X1133961D01*
G01Y335757D02*
X1134038D01*
G01D02*
Y375127D01*
X1133961D01*
G01Y383257D02*
X1134038D01*
G01D02*
Y422627D01*
X1133961D01*
G01Y430757D02*
X1134038D01*
G01D02*
Y470127D01*
X1133961D01*
G01Y478257D02*
X1134038D01*
G01D02*
Y517627D01*
X1133961D01*
G01X1185733Y83000D02*
X1186050Y82500D01*
X1186430Y82167D01*
X1186873Y82000D01*
X1187380Y82167D01*
X1187760Y82500D01*
X1188140Y83000D01*
X1188267Y83667D01*
Y87000D01*
G01X1190833Y82000D02*
Y87000D01*
X1192353D01*
X1192860Y86750D01*
X1193240Y86167D01*
X1193367Y85500D01*
X1193240Y84833D01*
X1192923Y84333D01*
X1192353Y84083D01*
X1190833D01*
G01X1195807Y83000D02*
X1196187Y82417D01*
X1196693Y82083D01*
X1197263Y82000D01*
X1197770Y82083D01*
X1198277Y82500D01*
X1198593Y83000D01*
X1198657Y83500D01*
X1198530Y84083D01*
X1198087Y84500D01*
X1197643Y84667D01*
X1197073D01*
G01X1197643D02*
X1198023Y84917D01*
X1198340Y85333D01*
X1198467Y85833D01*
X1198340Y86333D01*
X1198023Y86750D01*
X1197453Y87000D01*
X1196883Y86917D01*
X1196313Y86583D01*
G01X1188550Y98333D02*
Y103333D01*
X1187790Y102333D01*
G01Y98333D02*
X1189310D01*
G01X1192827Y100000D02*
X1194473D01*
G01X1197547Y102500D02*
X1197927Y103000D01*
X1198370Y103250D01*
X1198877Y103333D01*
X1199510Y103166D01*
X1199953Y102750D01*
X1200080Y102250D01*
X1200017Y101750D01*
X1199763Y101333D01*
X1198497Y100500D01*
X1197927Y99916D01*
X1197547Y99083D01*
X1197420Y98333D01*
X1200080D01*
G01X1207747D02*
Y103333D01*
X1210153D01*
G01X1209267Y100916D02*
X1207747D01*
G01X1212403Y98333D02*
Y103333D01*
X1214050Y99166D01*
X1215697Y103333D01*
Y98333D01*
G01X1217250Y96666D02*
X1221050D01*
G01X1222920Y98333D02*
Y103333D01*
G01X1225580D02*
Y98333D01*
G01Y100833D02*
X1222920D01*
G01X1228020Y99000D02*
X1228527Y98583D01*
X1229097Y98333D01*
X1229603D01*
X1230110Y98583D01*
X1230490Y99000D01*
X1230680Y99583D01*
X1230553Y100166D01*
X1230237Y100666D01*
X1229667Y101000D01*
X1228907Y101166D01*
X1228463Y101500D01*
X1228273Y102083D01*
X1228400Y102666D01*
X1228717Y103083D01*
X1229160Y103333D01*
X1229603D01*
X1230047Y103166D01*
X1230427Y102750D01*
G01X1235843Y102916D02*
X1235463Y103166D01*
X1235020Y103333D01*
X1234513D01*
X1233943Y103083D01*
X1233500Y102666D01*
X1233183Y102166D01*
X1232930Y101333D01*
X1232867Y100583D01*
X1232993Y99833D01*
X1233183Y99333D01*
X1233563Y98833D01*
X1234007Y98500D01*
X1234450Y98333D01*
X1234893D01*
X1235337Y98500D01*
X1235717Y98750D01*
X1236033Y99083D01*
G01X1237650Y96666D02*
X1241450D01*
G01X1245917Y98333D02*
X1243383D01*
Y103333D01*
X1245917D01*
G01X1244903Y100916D02*
X1243383D01*
G01X1248293Y98333D02*
Y103333D01*
X1251207Y98333D01*
Y103333D01*
G01X1252950Y96666D02*
X1256750D01*
G01X1260457Y101000D02*
X1260710Y101250D01*
X1260900Y101666D01*
X1261027Y102250D01*
X1260900Y102750D01*
X1260647Y103083D01*
X1260203Y103333D01*
X1258493D01*
Y98333D01*
X1260583D01*
X1261027Y98666D01*
X1261280Y99166D01*
X1261407Y99750D01*
X1261280Y100333D01*
X1260900Y100833D01*
X1260457Y101000D01*
X1258493D01*
G01X1263657Y103333D02*
Y99750D01*
X1263910Y99000D01*
X1264417Y98500D01*
X1265050Y98333D01*
X1265683Y98500D01*
X1266190Y99000D01*
X1266443Y99750D01*
Y103333D01*
G01X1268820Y99000D02*
X1269327Y98583D01*
X1269897Y98333D01*
X1270403D01*
X1270910Y98583D01*
X1271290Y99000D01*
X1271480Y99583D01*
X1271353Y100166D01*
X1271037Y100666D01*
X1270467Y101000D01*
X1269707Y101166D01*
X1269263Y101500D01*
X1269073Y102083D01*
X1269200Y102666D01*
X1269517Y103083D01*
X1269960Y103333D01*
X1270403D01*
X1270847Y103166D01*
X1271227Y102750D01*
G01X1275757Y101000D02*
X1276010Y101250D01*
X1276200Y101666D01*
X1276327Y102250D01*
X1276200Y102750D01*
X1275947Y103083D01*
X1275503Y103333D01*
X1273793D01*
Y98333D01*
X1275883D01*
X1276327Y98666D01*
X1276580Y99166D01*
X1276707Y99750D01*
X1276580Y100333D01*
X1276200Y100833D01*
X1275757Y101000D01*
X1273793D01*
G01X1278767Y98333D02*
X1280350Y103333D01*
X1281933Y98333D01*
G01X1281363Y100083D02*
X1279337D01*
G01X1284183Y98333D02*
Y103333D01*
X1285767D01*
X1286273Y103083D01*
X1286590Y102750D01*
X1286717Y102083D01*
X1286590Y101416D01*
X1286210Y101000D01*
X1285767Y100750D01*
X1284183D01*
G01X1285767D02*
X1286717Y98333D01*
G01X1187447Y94500D02*
X1187827Y95000D01*
X1188270Y95250D01*
X1188777Y95333D01*
X1189410Y95166D01*
X1189853Y94750D01*
X1189980Y94250D01*
X1189917Y93750D01*
X1189663Y93333D01*
X1188397Y92500D01*
X1187827Y91916D01*
X1187447Y91083D01*
X1187320Y90333D01*
X1189980D01*
G01X1192927Y92000D02*
X1194573D01*
G01X1197457Y91333D02*
X1197837Y90750D01*
X1198343Y90416D01*
X1198913Y90333D01*
X1199420Y90416D01*
X1199927Y90833D01*
X1200243Y91333D01*
X1200307Y91833D01*
X1200180Y92416D01*
X1199737Y92833D01*
X1199293Y93000D01*
X1198723D01*
G01X1199293D02*
X1199673Y93250D01*
X1199990Y93666D01*
X1200117Y94166D01*
X1199990Y94666D01*
X1199673Y95083D01*
X1199103Y95333D01*
X1198533Y95250D01*
X1197963Y94916D01*
G01X1207847Y90333D02*
Y95333D01*
X1210253D01*
G01X1209367Y92916D02*
X1207847D01*
G01X1212503Y90333D02*
Y95333D01*
X1214150Y91166D01*
X1215797Y95333D01*
Y90333D01*
G01X1217350Y88666D02*
X1221150D01*
G01X1223020Y90333D02*
Y95333D01*
G01X1225680D02*
Y90333D01*
G01Y92833D02*
X1223020D01*
G01X1228120Y91000D02*
X1228627Y90583D01*
X1229197Y90333D01*
X1229703D01*
X1230210Y90583D01*
X1230590Y91000D01*
X1230780Y91583D01*
X1230653Y92166D01*
X1230337Y92666D01*
X1229767Y93000D01*
X1229007Y93166D01*
X1228563Y93500D01*
X1228373Y94083D01*
X1228500Y94666D01*
X1228817Y95083D01*
X1229260Y95333D01*
X1229703D01*
X1230147Y95166D01*
X1230527Y94750D01*
G01X1235943Y94916D02*
X1235563Y95166D01*
X1235120Y95333D01*
X1234613D01*
X1234043Y95083D01*
X1233600Y94666D01*
X1233283Y94166D01*
X1233030Y93333D01*
X1232967Y92583D01*
X1233093Y91833D01*
X1233283Y91333D01*
X1233663Y90833D01*
X1234107Y90500D01*
X1234550Y90333D01*
X1234993D01*
X1235437Y90500D01*
X1235817Y90750D01*
X1236133Y91083D01*
G01X1237750Y88666D02*
X1241550D01*
G01X1246017Y90333D02*
X1243483D01*
Y95333D01*
X1246017D01*
G01X1245003Y92916D02*
X1243483D01*
G01X1248393Y90333D02*
Y95333D01*
X1251307Y90333D01*
Y95333D01*
G01X1253050Y88666D02*
X1256850D01*
G01X1258847Y90333D02*
Y95333D01*
X1261253D01*
G01X1260367Y92916D02*
X1258847D01*
G01X1263757Y95333D02*
Y91750D01*
X1264010Y91000D01*
X1264517Y90500D01*
X1265150Y90333D01*
X1265783Y90500D01*
X1266290Y91000D01*
X1266543Y91750D01*
Y95333D01*
G01X1268920Y91000D02*
X1269427Y90583D01*
X1269997Y90333D01*
X1270503D01*
X1271010Y90583D01*
X1271390Y91000D01*
X1271580Y91583D01*
X1271453Y92166D01*
X1271137Y92666D01*
X1270567Y93000D01*
X1269807Y93166D01*
X1269363Y93500D01*
X1269173Y94083D01*
X1269300Y94666D01*
X1269617Y95083D01*
X1270060Y95333D01*
X1270503D01*
X1270947Y95166D01*
X1271327Y94750D01*
G01X1276617Y90333D02*
X1274083D01*
Y95333D01*
X1276617D01*
G01X1275603Y92916D02*
X1274083D01*
G01X1170307Y81520D02*
X1170537Y81158D01*
X1170843Y80952D01*
X1171188Y80900D01*
X1171495Y80952D01*
X1171802Y81210D01*
X1171993Y81520D01*
X1172032Y81830D01*
X1171955Y82192D01*
X1171687Y82450D01*
X1171418Y82553D01*
X1171073D01*
G01X1171418D02*
X1171648Y82708D01*
X1171840Y82967D01*
X1171917Y83277D01*
X1171840Y83587D01*
X1171648Y83845D01*
X1171303Y84000D01*
X1170958Y83948D01*
X1170613Y83742D01*
G01X1187870Y105500D02*
Y110500D01*
G01X1190530D02*
Y105500D01*
G01Y108000D02*
X1187870D01*
G01X1192970Y106167D02*
X1193477Y105750D01*
X1194047Y105500D01*
X1194553D01*
X1195060Y105750D01*
X1195440Y106167D01*
X1195630Y106750D01*
X1195503Y107333D01*
X1195187Y107833D01*
X1194617Y108167D01*
X1193857Y108333D01*
X1193413Y108667D01*
X1193223Y109250D01*
X1193350Y109833D01*
X1193667Y110250D01*
X1194110Y110500D01*
X1194553D01*
X1194997Y110333D01*
X1195377Y109917D01*
G01X1200793Y110083D02*
X1200413Y110333D01*
X1199970Y110500D01*
X1199463D01*
X1198893Y110250D01*
X1198450Y109833D01*
X1198133Y109333D01*
X1197880Y108500D01*
X1197817Y107750D01*
X1197943Y107000D01*
X1198133Y106500D01*
X1198513Y106000D01*
X1198957Y105667D01*
X1199400Y105500D01*
X1199843D01*
X1200287Y105667D01*
X1200667Y105917D01*
X1200983Y106250D01*
G01X1210867Y105500D02*
X1208333D01*
Y110500D01*
X1210867D01*
G01X1209853Y108083D02*
X1208333D01*
G01X1213243Y105500D02*
Y110500D01*
X1216157Y105500D01*
Y110500D01*
G01X1218217Y105500D02*
X1219800Y110500D01*
X1221383Y105500D01*
G01X1220813Y107250D02*
X1218787D01*
G01X1225407Y108167D02*
X1225660Y108417D01*
X1225850Y108833D01*
X1225977Y109417D01*
X1225850Y109917D01*
X1225597Y110250D01*
X1225153Y110500D01*
X1223443D01*
Y105500D01*
X1225533D01*
X1225977Y105833D01*
X1226230Y106333D01*
X1226357Y106917D01*
X1226230Y107500D01*
X1225850Y108000D01*
X1225407Y108167D01*
X1223443D01*
G01X1228733Y110500D02*
Y105500D01*
X1231267D01*
G01X1236367D02*
X1233833D01*
Y110500D01*
X1236367D01*
G01X1235353Y108083D02*
X1233833D01*
G01X1245807Y108167D02*
X1246060Y108417D01*
X1246250Y108833D01*
X1246377Y109417D01*
X1246250Y109917D01*
X1245997Y110250D01*
X1245553Y110500D01*
X1243843D01*
Y105500D01*
X1245933D01*
X1246377Y105833D01*
X1246630Y106333D01*
X1246757Y106917D01*
X1246630Y107500D01*
X1246250Y108000D01*
X1245807Y108167D01*
X1243843D01*
G01X1250400Y105500D02*
Y107750D01*
X1249133Y110500D01*
G01X1251667D02*
X1250400Y107750D01*
G01X1254233Y105500D02*
Y110500D01*
X1255753D01*
X1256260Y110250D01*
X1256640Y109667D01*
X1256767Y109000D01*
X1256640Y108333D01*
X1256323Y107833D01*
X1255753Y107583D01*
X1254233D01*
G01X1259017Y105500D02*
X1260600Y110500D01*
X1262183Y105500D01*
G01X1261613Y107250D02*
X1259587D01*
G01X1264370Y106167D02*
X1264877Y105750D01*
X1265447Y105500D01*
X1265953D01*
X1266460Y105750D01*
X1266840Y106167D01*
X1267030Y106750D01*
X1266903Y107333D01*
X1266587Y107833D01*
X1266017Y108167D01*
X1265257Y108333D01*
X1264813Y108667D01*
X1264623Y109250D01*
X1264750Y109833D01*
X1265067Y110250D01*
X1265510Y110500D01*
X1265953D01*
X1266397Y110333D01*
X1266777Y109917D01*
G01X1269470Y106167D02*
X1269977Y105750D01*
X1270547Y105500D01*
X1271053D01*
X1271560Y105750D01*
X1271940Y106167D01*
X1272130Y106750D01*
X1272003Y107333D01*
X1271687Y107833D01*
X1271117Y108167D01*
X1270357Y108333D01*
X1269913Y108667D01*
X1269723Y109250D01*
X1269850Y109833D01*
X1270167Y110250D01*
X1270610Y110500D01*
X1271053D01*
X1271497Y110333D01*
X1271877Y109917D01*
G01X1168400Y107800D02*
X1178600D01*
Y103200D01*
X1168400D01*
Y107800D01*
G01X1182600Y118727D02*
Y116487D01*
G01X1184225Y117700D02*
X1180975D01*
G01X1169794Y125242D02*
X1166694D01*
Y126162D01*
X1166849Y126469D01*
X1167211Y126699D01*
X1167624Y126776D01*
X1168037Y126699D01*
X1168347Y126507D01*
X1168502Y126162D01*
Y125242D01*
G01X1169794Y128266D02*
X1166694D01*
Y129032D01*
X1166849Y129339D01*
X1167056Y129569D01*
X1167366Y129761D01*
X1167727Y129914D01*
X1168244Y129952D01*
X1168761Y129914D01*
X1169122Y129761D01*
X1169432Y129569D01*
X1169639Y129339D01*
X1169794Y129032D01*
Y128266D01*
G01Y132132D02*
X1169122Y132209D01*
X1168554Y132324D01*
X1168037Y132477D01*
X1167469Y132669D01*
X1166694Y132976D01*
Y131442D01*
G01X1195805Y162235D02*
Y125095D01*
X1171317D01*
Y162135D01*
G01X1170400Y113100D02*
X1176600D01*
Y109900D01*
X1170400D01*
Y113100D01*
G01X1162700Y151000D02*
X1169300D01*
Y138000D01*
X1162700D01*
Y151000D01*
G01X1171317Y161609D02*
Y160322D01*
G01Y161222D02*
Y160022D01*
G01Y159928D02*
Y162335D01*
G01X1183561Y139259D02*
Y141059D01*
G01X1187561Y141459D02*
X1179561D01*
X1183561Y146459D01*
X1187561Y141459D01*
G01X1188561Y146459D02*
X1178561D01*
G01X1183561D02*
Y148259D01*
G01X1193100Y168413D02*
Y165987D01*
G01X1171317Y164378D02*
X1195805D01*
G01X1171317Y164178D02*
X1195805D01*
G01X1171317Y163978D02*
X1195805D01*
G01X1171317Y163578D02*
X1195805D01*
G01X1171317Y163178D02*
X1195805D01*
G01X1171317Y162878D02*
X1195805D01*
G01Y162135D02*
Y164759D01*
X1171317D01*
Y162290D01*
G01Y161984D02*
X1195805D01*
G01X1171317D02*
X1195805D01*
G01X1171317Y161945D02*
X1195805D01*
G01X1171317Y161984D02*
X1195805D01*
G01X1171317Y162378D02*
X1195805D01*
G01X1175850Y169194D02*
X1190350D01*
Y219806D01*
X1175850D01*
Y169194D01*
G01X1174600Y191422D02*
X1171500D01*
Y192878D01*
G01X1172998Y192342D02*
Y191422D01*
G01X1174187Y194445D02*
X1174445Y194752D01*
X1174600Y195097D01*
Y195403D01*
X1174445Y195710D01*
X1174187Y195940D01*
X1173825Y196055D01*
X1173463Y195978D01*
X1173153Y195787D01*
X1172947Y195442D01*
X1172843Y194982D01*
X1172637Y194713D01*
X1172275Y194598D01*
X1171913Y194675D01*
X1171655Y194867D01*
X1171500Y195135D01*
Y195403D01*
X1171603Y195672D01*
X1171862Y195902D01*
G01X1174600Y198350D02*
X1171500D01*
X1172120Y197890D01*
G01X1174600D02*
Y198810D01*
G01X1168383Y289250D02*
Y292350D01*
X1169303D01*
X1169610Y292195D01*
X1169840Y291833D01*
X1169917Y291420D01*
X1169840Y291007D01*
X1169648Y290697D01*
X1169303Y290542D01*
X1168383D01*
G01X1171483Y289250D02*
Y292350D01*
X1172442D01*
X1172748Y292195D01*
X1172940Y291988D01*
X1173017Y291575D01*
X1172940Y291162D01*
X1172710Y290903D01*
X1172442Y290748D01*
X1171483D01*
G01X1172442D02*
X1173017Y289250D01*
G01X1174507Y289870D02*
X1174737Y289508D01*
X1175043Y289302D01*
X1175388Y289250D01*
X1175695Y289302D01*
X1176002Y289560D01*
X1176193Y289870D01*
X1176232Y290180D01*
X1176155Y290542D01*
X1175887Y290800D01*
X1175618Y290903D01*
X1175273D01*
G01X1175618D02*
X1175848Y291058D01*
X1176040Y291317D01*
X1176117Y291627D01*
X1176040Y291937D01*
X1175848Y292195D01*
X1175503Y292350D01*
X1175158Y292298D01*
X1174813Y292092D01*
G01X1178450Y289250D02*
Y292350D01*
X1177990Y291730D01*
G01Y289250D02*
X1178910D01*
G01X1180707Y289715D02*
X1180937Y289457D01*
X1181205Y289302D01*
X1181550Y289250D01*
X1181895Y289353D01*
X1182163Y289560D01*
X1182355Y289922D01*
X1182393Y290335D01*
X1182317Y290748D01*
X1182125Y291007D01*
X1181857Y291213D01*
X1181588Y291265D01*
X1181320Y291213D01*
X1180975Y291007D01*
X1181090Y292350D01*
X1182125D01*
G01X1195351Y322042D02*
Y293842D01*
X1163951D01*
Y322042D01*
X1195351D01*
G01X1176511Y326450D02*
X1166311D01*
Y331050D01*
X1176511D01*
Y326450D01*
G01X1182311Y331050D02*
X1192511D01*
Y326450D01*
X1182311D01*
Y331050D01*
G01X1192511Y333450D02*
X1182311D01*
Y338050D01*
X1192511D01*
Y333450D01*
G01X1166311Y338050D02*
X1176511D01*
Y333450D01*
X1166311D01*
Y338050D01*
G01X1176511Y339450D02*
X1166311D01*
Y344050D01*
X1176511D01*
Y339450D01*
G01X1182311Y344050D02*
X1192511D01*
Y339450D01*
X1182311D01*
Y344050D01*
G01X1182511Y345150D02*
X1176311D01*
Y348350D01*
X1182511D01*
Y345150D01*
G01X1166383Y432250D02*
Y435350D01*
X1167303D01*
X1167610Y435195D01*
X1167840Y434833D01*
X1167917Y434420D01*
X1167840Y434007D01*
X1167648Y433697D01*
X1167303Y433542D01*
X1166383D01*
G01X1169483Y432250D02*
Y435350D01*
X1170442D01*
X1170748Y435195D01*
X1170940Y434988D01*
X1171017Y434575D01*
X1170940Y434162D01*
X1170710Y433903D01*
X1170442Y433748D01*
X1169483D01*
G01X1170442D02*
X1171017Y432250D01*
G01X1173350D02*
Y435350D01*
X1172890Y434730D01*
G01Y432250D02*
X1173810D01*
G01X1195440Y464542D02*
Y436342D01*
X1164040D01*
Y464542D01*
X1195440D01*
G01X1182400Y486550D02*
X1192600D01*
Y481950D01*
X1182400D01*
Y486550D01*
G01X1176600Y481950D02*
X1166400D01*
Y486550D01*
X1176600D01*
Y481950D01*
G01Y468950D02*
X1166400D01*
Y473550D01*
X1176600D01*
Y468950D01*
G01X1182400Y473550D02*
X1192600D01*
Y468950D01*
X1182400D01*
Y473550D01*
G01X1176600Y475950D02*
X1166400D01*
Y480550D01*
X1176600D01*
Y475950D01*
G01X1182400Y480550D02*
X1192600D01*
Y475950D01*
X1182400D01*
Y480550D01*
G01X1182600Y487650D02*
X1176400D01*
Y490850D01*
X1182600D01*
Y487650D01*
G01X1200552Y422224D02*
X1281575D01*
Y151634D01*
X1200552D01*
Y316500D01*
G01X1195805Y162335D02*
Y157455D01*
G01Y159822D02*
Y159928D01*
G01X1212363Y186000D02*
Y389500D01*
G01X1213500Y163445D02*
X1212363D01*
Y165000D01*
G01X1195805Y162135D02*
Y161609D01*
G01X1195512Y162022D02*
X1195312Y162009D01*
G01X1200552Y347500D02*
Y422224D01*
G01X1216183Y424620D02*
X1216375Y424310D01*
X1216605Y424103D01*
X1216873Y424000D01*
X1217180Y424103D01*
X1217410Y424310D01*
X1217640Y424620D01*
X1217717Y425033D01*
Y427100D01*
G01X1219207Y424465D02*
X1219437Y424207D01*
X1219705Y424052D01*
X1220050Y424000D01*
X1220395Y424103D01*
X1220663Y424310D01*
X1220855Y424672D01*
X1220893Y425085D01*
X1220817Y425498D01*
X1220625Y425757D01*
X1220357Y425963D01*
X1220088Y426015D01*
X1219820Y425963D01*
X1219475Y425757D01*
X1219590Y427100D01*
X1220625D01*
G01X1212363Y409000D02*
Y410413D01*
G01X1234722Y-629244D02*
Y-626144D01*
X1235642D01*
X1235949Y-626299D01*
X1236179Y-626661D01*
X1236256Y-627074D01*
X1236179Y-627487D01*
X1235987Y-627797D01*
X1235642Y-627952D01*
X1234722D01*
G01X1237899Y-629347D02*
X1239279Y-626144D01*
G01X1240807Y-629244D02*
Y-626144D01*
X1242571Y-629244D01*
Y-626144D01*
G01X1244789Y-629347D02*
X1244712Y-629296D01*
Y-629192D01*
X1244789Y-629141D01*
X1244866Y-629192D01*
Y-629296D01*
X1244789Y-629347D01*
G01Y-627952D02*
X1244712Y-627901D01*
Y-627797D01*
X1244789Y-627746D01*
X1244866Y-627797D01*
Y-627901D01*
X1244789Y-627952D01*
G01X1247046Y-629244D02*
Y-626144D01*
X1247812D01*
X1248119Y-626299D01*
X1248349Y-626506D01*
X1248541Y-626816D01*
X1248694Y-627177D01*
X1248732Y-627694D01*
X1248694Y-628211D01*
X1248541Y-628572D01*
X1248349Y-628882D01*
X1248119Y-629089D01*
X1247812Y-629244D01*
X1247046D01*
G01X1250031D02*
X1250989Y-626144D01*
X1251947Y-629244D01*
G01X1251602Y-628159D02*
X1250376D01*
G01X1254089Y-626144D02*
X1253782Y-626247D01*
X1253552Y-626506D01*
X1253399Y-626816D01*
X1253284Y-627229D01*
X1253246Y-627694D01*
X1253284Y-628159D01*
X1253399Y-628572D01*
X1253552Y-628882D01*
X1253782Y-629141D01*
X1254089Y-629244D01*
X1254396Y-629141D01*
X1254626Y-628882D01*
X1254779Y-628572D01*
X1254894Y-628159D01*
X1254932Y-627694D01*
X1254894Y-627229D01*
X1254779Y-626816D01*
X1254626Y-626506D01*
X1254396Y-626247D01*
X1254089Y-626144D01*
G01X1256461Y-629244D02*
Y-626144D01*
X1257917D01*
G01X1257381Y-627642D02*
X1256461D01*
G01X1260289Y-626144D02*
X1259982Y-626247D01*
X1259752Y-626506D01*
X1259599Y-626816D01*
X1259484Y-627229D01*
X1259446Y-627694D01*
X1259484Y-628159D01*
X1259599Y-628572D01*
X1259752Y-628882D01*
X1259982Y-629141D01*
X1260289Y-629244D01*
X1260596Y-629141D01*
X1260826Y-628882D01*
X1260979Y-628572D01*
X1261094Y-628159D01*
X1261132Y-627694D01*
X1261094Y-627229D01*
X1260979Y-626816D01*
X1260826Y-626506D01*
X1260596Y-626247D01*
X1260289Y-626144D01*
G01X1263389D02*
Y-629244D01*
G01X1262507Y-626144D02*
X1264271D01*
G01X1265722Y-629244D02*
Y-626144D01*
X1266642D01*
X1266949Y-626299D01*
X1267179Y-626661D01*
X1267256Y-627074D01*
X1267179Y-627487D01*
X1266987Y-627797D01*
X1266642Y-627952D01*
X1265722D01*
G01X1269896Y-627591D02*
X1270049Y-627436D01*
X1270164Y-627177D01*
X1270241Y-626816D01*
X1270164Y-626506D01*
X1270011Y-626299D01*
X1269742Y-626144D01*
X1268707D01*
Y-629244D01*
X1269972D01*
X1270241Y-629037D01*
X1270394Y-628727D01*
X1270471Y-628366D01*
X1270394Y-628004D01*
X1270164Y-627694D01*
X1269896Y-627591D01*
X1268707D01*
G01X1271731Y-629244D02*
X1272689Y-626144D01*
X1273647Y-629244D01*
G01X1273302Y-628159D02*
X1272076D01*
G01X1275061Y-629244D02*
Y-626144D01*
X1276517D01*
G01X1275981Y-627642D02*
X1275061D01*
G01X1278889Y-626144D02*
X1278582Y-626247D01*
X1278352Y-626506D01*
X1278199Y-626816D01*
X1278084Y-627229D01*
X1278046Y-627694D01*
X1278084Y-628159D01*
X1278199Y-628572D01*
X1278352Y-628882D01*
X1278582Y-629141D01*
X1278889Y-629244D01*
X1279196Y-629141D01*
X1279426Y-628882D01*
X1279579Y-628572D01*
X1279694Y-628159D01*
X1279732Y-627694D01*
X1279694Y-627229D01*
X1279579Y-626816D01*
X1279426Y-626506D01*
X1279196Y-626247D01*
X1278889Y-626144D01*
G01X1241500Y410413D02*
X1269764D01*
Y163445D01*
X1239000D01*
G01X1232633Y426000D02*
Y431000D01*
X1234153D01*
X1234660Y430750D01*
X1235040Y430167D01*
X1235167Y429500D01*
X1235040Y428833D01*
X1234723Y428333D01*
X1234153Y428083D01*
X1232633D01*
G01X1239000Y426000D02*
X1238493Y426083D01*
X1238050Y426417D01*
X1237670Y426917D01*
X1237417Y427500D01*
X1237290Y428167D01*
Y428833D01*
X1237417Y429500D01*
X1237670Y430083D01*
X1238050Y430583D01*
X1238493Y430917D01*
X1239000Y431000D01*
X1239507Y430917D01*
X1239950Y430583D01*
X1240330Y430083D01*
X1240583Y429500D01*
X1240710Y428833D01*
Y428167D01*
X1240583Y427500D01*
X1240330Y426917D01*
X1239950Y426417D01*
X1239507Y426083D01*
X1239000Y426000D01*
G01X1242200Y431000D02*
X1243087Y426000D01*
X1244100Y431000D01*
X1245113Y426000D01*
X1246000Y431000D01*
G01X1250467Y426000D02*
X1247933D01*
Y431000D01*
X1250467D01*
G01X1249453Y428583D02*
X1247933D01*
G01X1253033Y426000D02*
Y431000D01*
X1254617D01*
X1255123Y430750D01*
X1255440Y430417D01*
X1255567Y429750D01*
X1255440Y429083D01*
X1255060Y428667D01*
X1254617Y428417D01*
X1253033D01*
G01X1254617D02*
X1255567Y426000D01*
G01X1265893Y430583D02*
X1265513Y430833D01*
X1265070Y431000D01*
X1264563D01*
X1263993Y430750D01*
X1263550Y430333D01*
X1263233Y429833D01*
X1262980Y429000D01*
X1262917Y428250D01*
X1263043Y427500D01*
X1263233Y427000D01*
X1263613Y426500D01*
X1264057Y426167D01*
X1264500Y426000D01*
X1264943D01*
X1265387Y426167D01*
X1265767Y426417D01*
X1266083Y426750D01*
G01X1269600Y426000D02*
X1269093Y426083D01*
X1268650Y426417D01*
X1268270Y426917D01*
X1268017Y427500D01*
X1267890Y428167D01*
Y428833D01*
X1268017Y429500D01*
X1268270Y430083D01*
X1268650Y430583D01*
X1269093Y430917D01*
X1269600Y431000D01*
X1270107Y430917D01*
X1270550Y430583D01*
X1270930Y430083D01*
X1271183Y429500D01*
X1271310Y428833D01*
Y428167D01*
X1271183Y427500D01*
X1270930Y426917D01*
X1270550Y426417D01*
X1270107Y426083D01*
X1269600Y426000D01*
G01X1273243D02*
Y431000D01*
X1276157Y426000D01*
Y431000D01*
G01X1278343Y426000D02*
Y431000D01*
X1281257Y426000D01*
Y431000D01*
G01X1236345Y544000D02*
Y547100D01*
G01X1237955D02*
Y544000D01*
G01Y545550D02*
X1236345D01*
G01X1240250Y544000D02*
Y547100D01*
X1239790Y546480D01*
G01Y544000D02*
X1240710D01*
G01X1242698Y544362D02*
X1242967Y544103D01*
X1243273Y544000D01*
X1243580Y544103D01*
X1243848Y544413D01*
X1244040Y544878D01*
X1244117Y545343D01*
Y545912D01*
X1244040Y546377D01*
X1243848Y546790D01*
X1243618Y546997D01*
X1243350Y547100D01*
X1243043Y546997D01*
X1242813Y546790D01*
X1242660Y546480D01*
X1242583Y546067D01*
X1242660Y545705D01*
X1242852Y545343D01*
X1243082Y545137D01*
X1243350Y545085D01*
X1243657Y545188D01*
X1243887Y545447D01*
X1244117Y545912D01*
G01X1265095Y52450D02*
Y55550D01*
G01X1266705D02*
Y52450D01*
G01Y54000D02*
X1265095D01*
G01X1268272Y55033D02*
X1268502Y55343D01*
X1268770Y55498D01*
X1269077Y55550D01*
X1269460Y55447D01*
X1269728Y55188D01*
X1269805Y54878D01*
X1269767Y54568D01*
X1269613Y54310D01*
X1268847Y53793D01*
X1268502Y53432D01*
X1268272Y52915D01*
X1268195Y52450D01*
X1269805D01*
G01X1272100Y55550D02*
X1271793Y55447D01*
X1271563Y55188D01*
X1271410Y54878D01*
X1271295Y54465D01*
X1271257Y54000D01*
X1271295Y53535D01*
X1271410Y53122D01*
X1271563Y52812D01*
X1271793Y52553D01*
X1272100Y52450D01*
X1272407Y52553D01*
X1272637Y52812D01*
X1272790Y53122D01*
X1272905Y53535D01*
X1272943Y54000D01*
X1272905Y54465D01*
X1272790Y54878D01*
X1272637Y55188D01*
X1272407Y55447D01*
X1272100Y55550D01*
G01X1279000Y261633D02*
X1271500D01*
Y263873D01*
X1271875Y264620D01*
X1272750Y265180D01*
X1273750Y265367D01*
X1274750Y265180D01*
X1275500Y264713D01*
X1275875Y263873D01*
Y261633D01*
G01X1279000Y269133D02*
X1271500D01*
Y271467D01*
X1271875Y272213D01*
X1272375Y272680D01*
X1273375Y272867D01*
X1274375Y272680D01*
X1275000Y272120D01*
X1275375Y271467D01*
Y269133D01*
G01Y271467D02*
X1279000Y272867D01*
G01Y280367D02*
Y276633D01*
X1271500D01*
Y280367D01*
G01X1275125Y278873D02*
Y276633D01*
G01X1278000Y284040D02*
X1278625Y284787D01*
X1279000Y285627D01*
Y286373D01*
X1278625Y287120D01*
X1278000Y287680D01*
X1277125Y287960D01*
X1276250Y287773D01*
X1275500Y287307D01*
X1275000Y286467D01*
X1274750Y285347D01*
X1274250Y284693D01*
X1273375Y284413D01*
X1272500Y284600D01*
X1271875Y285067D01*
X1271500Y285720D01*
Y286373D01*
X1271750Y287027D01*
X1272375Y287587D01*
G01X1278000Y291540D02*
X1278625Y292287D01*
X1279000Y293127D01*
Y293873D01*
X1278625Y294620D01*
X1278000Y295180D01*
X1277125Y295460D01*
X1276250Y295273D01*
X1275500Y294807D01*
X1275000Y293967D01*
X1274750Y292847D01*
X1274250Y292193D01*
X1273375Y291913D01*
X1272500Y292100D01*
X1271875Y292567D01*
X1271500Y293220D01*
Y293873D01*
X1271750Y294527D01*
X1272375Y295087D01*
G01X1276500Y299787D02*
Y302213D01*
G01X1279000Y306727D02*
X1271500D01*
Y310273D01*
G01X1275125Y308967D02*
Y306727D01*
G01X1271500Y314880D02*
Y317120D01*
G01Y316000D02*
X1279000D01*
G01Y314880D02*
Y317120D01*
G01X1271500Y323500D02*
X1279000D01*
G01X1271500Y321353D02*
Y325647D01*
M02*
